# Altium SchDoc records: 10-M2_GPS.SchDoc
|HEADER=Protel for Windows - Schematic Capture Binary File Version 5.0|Weight=2656|MinorVersion=9
|RECORD=31|FontIdCount=4|Size1=10|FontName1=Times New Roman|Size2=10|Rotation2=90|FontName2=Times New Roman|Size3=10|Underline3=T|FontName3=Times New Roman|Size4=24|FontName4=Times New Roman|UseMBCS=T|IsBOC=T|HotSpotGridOn=T|HotSpotGridSize=4|SheetStyle=6|SystemFont=1|BorderOn=T|TitleBlockOn=T|SheetNumberSpaceSize=12|AreaColor=16317695|SnapGridOn=T|SnapGridSize=10|VisibleGridOn=T|VisibleGridSize=10|CustomX=1500|CustomY=950|CustomXZones=6|CustomYZones=4|CustomMarginWidth=20|Display_Unit=0
|RECORD=41|OwnerPartId=-1|Color=8388608|FontID=1|IsHidden=T|Text=*|Name=CurrentTime|ReadOnlyState=1
|RECORD=41|IndexInSheet=1|OwnerPartId=-1|Color=8388608|FontID=1|IsHidden=T|Text=*|Name=CurrentDate|ReadOnlyState=1
|RECORD=41|IndexInSheet=2|OwnerPartId=-1|Color=8388608|FontID=1|IsHidden=T|Text=*|Name=Time|ReadOnlyState=1
|RECORD=41|IndexInSheet=3|OwnerPartId=-1|Color=8388608|FontID=1|IsHidden=T|Text=*|Name=Date|ReadOnlyState=1
|RECORD=41|IndexInSheet=4|OwnerPartId=-1|Color=8388608|FontID=1|IsHidden=T|Text=*|Name=DocumentFullPathAndName|ReadOnlyState=1
|RECORD=41|IndexInSheet=5|OwnerPartId=-1|Color=8388608|FontID=1|IsHidden=T|Text=*|Name=DocumentName|ReadOnlyState=1
|RECORD=41|IndexInSheet=6|OwnerPartId=-1|Color=8388608|FontID=1|IsHidden=T|Text=*|Name=ModifiedDate|ReadOnlyState=1
|RECORD=41|IndexInSheet=7|OwnerPartId=-1|Color=8388608|FontID=1|IsHidden=T|Text=*|Name=ApprovedBy|ReadOnlyState=1
|RECORD=41|IndexInSheet=8|OwnerPartId=-1|Color=8388608|FontID=1|IsHidden=T|Text=*|Name=CheckedBy|ReadOnlyState=1
|RECORD=41|IndexInSheet=9|OwnerPartId=-1|Color=8388608|FontID=1|IsHidden=T|Text=*|Name=Author|ReadOnlyState=1
|RECORD=41|IndexInSheet=10|OwnerPartId=-1|Color=8388608|FontID=1|IsHidden=T|Text=*|Name=CompanyName|ReadOnlyState=1
|RECORD=41|IndexInSheet=11|OwnerPartId=-1|Color=8388608|FontID=1|IsHidden=T|Text=*|Name=DrawnBy|ReadOnlyState=1
|RECORD=41|IndexInSheet=12|OwnerPartId=-1|Color=8388608|FontID=1|IsHidden=T|Text=*|Name=Engineer|ReadOnlyState=1
|RECORD=41|IndexInSheet=13|OwnerPartId=-1|Color=8388608|FontID=1|IsHidden=T|Text=*|Name=Organization|ReadOnlyState=1
|RECORD=41|IndexInSheet=14|OwnerPartId=-1|Color=8388608|FontID=1|IsHidden=T|Text=*|Name=Address1|ReadOnlyState=1
|RECORD=41|IndexInSheet=15|OwnerPartId=-1|Color=8388608|FontID=1|IsHidden=T|Text=*|Name=Address2|ReadOnlyState=1
|RECORD=41|IndexInSheet=16|OwnerPartId=-1|Color=8388608|FontID=1|IsHidden=T|Text=*|Name=Address3|ReadOnlyState=1
|RECORD=41|IndexInSheet=17|OwnerPartId=-1|Color=8388608|FontID=1|IsHidden=T|Text=*|Name=Address4|ReadOnlyState=1
|RECORD=41|IndexInSheet=18|OwnerPartId=-1|Color=8388608|FontID=1|IsHidden=T|Text=*|Name=Title|ReadOnlyState=1
|RECORD=41|IndexInSheet=19|OwnerPartId=-1|Color=8388608|FontID=1|IsHidden=T|Text=*|Name=DocumentNumber|ReadOnlyState=1
|RECORD=41|IndexInSheet=20|OwnerPartId=-1|Color=8388608|FontID=1|IsHidden=T|Text=*|Name=Revision|ReadOnlyState=1
|RECORD=41|IndexInSheet=21|OwnerPartId=-1|Color=8388608|FontID=1|IsHidden=T|Text=*|Name=SheetNumber|ReadOnlyState=1
|RECORD=41|IndexInSheet=22|OwnerPartId=-1|Color=8388608|FontID=1|IsHidden=T|Text=*|Name=SheetTotal|ReadOnlyState=1
|RECORD=41|IndexInSheet=23|OwnerPartId=-1|Color=8388608|FontID=1|IsHidden=T|Text=*|Name=Rule|ReadOnlyState=1
|RECORD=41|IndexInSheet=24|OwnerPartId=-1|Color=8388608|FontID=1|IsHidden=T|Text=*|Name=ImagePath|ReadOnlyState=1
|RECORD=41|IndexInSheet=25|OwnerPartId=-1|Color=8388608|FontID=1|IsHidden=T|Text=*|Name=ProjectName|ReadOnlyState=1
|RECORD=41|IndexInSheet=26|OwnerPartId=-1|Color=8388608|FontID=1|IsHidden=T|Text=*|Name=Application_BuildNumber|ReadOnlyState=1
|RECORD=17|IndexInSheet=27|OwnerPartId=-1|Style=4|ShowNetName=T|Location.X=160|Location.Y=110|Orientation=3|Color=128|FontID=1|Text=GND
|RECORD=17|IndexInSheet=28|OwnerPartId=-1|ShowNetName=T|Location.X=460|Location.Y=820|Orientation=1|Color=128|FontID=1|Text=+3.3V
|RECORD=17|IndexInSheet=29|OwnerPartId=-1|Style=4|ShowNetName=T|Location.X=460|Location.Y=120|Orientation=3|Color=128|FontID=1|Text=GND
|RECORD=17|IndexInSheet=30|OwnerPartId=-1|ShowNetName=T|Location.X=510|Location.Y=400|Color=255|FontID=1|Text=GPS1_RST|IsCrossSheetConnector=T
|RECORD=4|IndexInSheet=31|OwnerPartId=-1|Location.X=400|Location.Y=890|Color=8388608|FontID=4|Text=Socket 2 Key B PCIe-based WWAN Adapter Pinout , table 3-21 in M.2 spec
|RECORD=17|IndexInSheet=32|OwnerPartId=-1|ShowNetName=T|Location.X=570|Location.Y=420|Color=255|FontID=1|Text=M2_GPS1_TP2|IsCrossSheetConnector=T
|RECORD=17|IndexInSheet=33|OwnerPartId=-1|ShowNetName=T|Location.X=290|Location.Y=550|Color=255|FontID=1|Text=M2_GPS1_TP1|IsCrossSheetConnector=T
|RECORD=17|IndexInSheet=34|OwnerPartId=-1|ShowNetName=T|Location.X=510|Location.Y=280|Color=255|FontID=1|Text=M2_GPS1_RX|IsCrossSheetConnector=T
|RECORD=17|IndexInSheet=35|OwnerPartId=-1|ShowNetName=T|Location.X=510|Location.Y=260|Color=255|FontID=1|Text=M2_GPS1_TX|IsCrossSheetConnector=T
|RECORD=17|IndexInSheet=36|OwnerPartId=-1|ShowNetName=T|Location.X=200|Location.Y=230|Color=255|FontID=1|Text=GPS1_RST|IsCrossSheetConnector=T
|RECORD=17|IndexInSheet=37|OwnerPartId=-1|ShowNetName=T|Location.X=530|Location.Y=500|Color=255|FontID=1|Text=GPS1_PIN13|IsCrossSheetConnector=T
|RECORD=17|IndexInSheet=38|OwnerPartId=-1|ShowNetName=T|Location.X=530|Location.Y=480|Color=255|FontID=1|Text=GPS1_PIN14|IsCrossSheetConnector=T
|RECORD=17|IndexInSheet=39|OwnerPartId=-1|ShowNetName=T|Location.X=530|Location.Y=460|Color=255|FontID=1|Text=GPS1_PIN15|IsCrossSheetConnector=T
|RECORD=17|IndexInSheet=40|OwnerPartId=-1|ShowNetName=T|Location.X=560|Location.Y=700|Color=255|FontID=1|Text=M2_GPS1_PIN11|IsCrossSheetConnector=T
|RECORD=17|IndexInSheet=41|OwnerPartId=-1|ShowNetName=T|Location.X=560|Location.Y=680|Color=255|FontID=1|Text=M2_GPS1_PIN12|IsCrossSheetConnector=T
|RECORD=1|LibReference=a14843ccfa78e5d0b739856168502fb|ComponentDescription=CONN M.2 FEMALE 67POS 0.020 GOLD|PartCount=3|DisplayModeCount=1|IndexInSheet=42|OwnerPartId=-1|Location.X=140|Location.Y=810|CurrentPartId=1|LibraryPath=*|SourceLibraryName=Altium Content Vault|TargetFileName=*|AreaColor=11599871|Color=128|PartIDLocked=T|DesignItemId=CMP-03365-000004-1|AllPinCount=69
|RECORD=14|OwnerIndex=43|IsNotAccesible=T|OwnerPartId=1|Location.X=70|Location.Y=110|Corner.X=120|Corner.Y=830|LineWidth=1|Color=128|AreaColor=11599871|IsSolid=T
|RECORD=8|OwnerIndex=43|IsNotAccesible=T|IndexInSheet=1|OwnerPartId=1|Location.X=95|Location.Y=810|Radius=3|SecondaryRadius=3|LineWidth=1|Color=16711680
|RECORD=13|OwnerIndex=43|IsNotAccesible=T|IndexInSheet=2|OwnerPartId=1|Location.X=98|Location.Y=810|Corner.X=120|Corner.Y=810|LineWidth=1|Color=16711680
|RECORD=8|OwnerIndex=43|IsNotAccesible=T|IndexInSheet=3|OwnerPartId=1|Location.X=95|Location.Y=790|Radius=3|SecondaryRadius=3|LineWidth=1|Color=16711680
|RECORD=13|OwnerIndex=43|IsNotAccesible=T|IndexInSheet=4|OwnerPartId=1|Location.X=98|Location.Y=790|Corner.X=120|Corner.Y=790|LineWidth=1|Color=16711680
|RECORD=8|OwnerIndex=43|IsNotAccesible=T|IndexInSheet=5|OwnerPartId=1|Location.X=95|Location.Y=770|Radius=3|SecondaryRadius=3|LineWidth=1|Color=16711680
|RECORD=13|OwnerIndex=43|IsNotAccesible=T|IndexInSheet=6|OwnerPartId=1|Location.X=98|Location.Y=770|Corner.X=120|Corner.Y=770|LineWidth=1|Color=16711680
|RECORD=8|OwnerIndex=43|IsNotAccesible=T|IndexInSheet=7|OwnerPartId=1|Location.X=95|Location.Y=750|Radius=3|SecondaryRadius=3|LineWidth=1|Color=16711680
|RECORD=13|OwnerIndex=43|IsNotAccesible=T|IndexInSheet=8|OwnerPartId=1|Location.X=98|Location.Y=750|Corner.X=120|Corner.Y=750|LineWidth=1|Color=16711680
|RECORD=8|OwnerIndex=43|IsNotAccesible=T|IndexInSheet=9|OwnerPartId=1|Location.X=95|Location.Y=730|Radius=3|SecondaryRadius=3|LineWidth=1|Color=16711680
|RECORD=13|OwnerIndex=43|IsNotAccesible=T|IndexInSheet=10|OwnerPartId=1|Location.X=98|Location.Y=730|Corner.X=120|Corner.Y=730|LineWidth=1|Color=16711680
|RECORD=8|OwnerIndex=43|IsNotAccesible=T|IndexInSheet=11|OwnerPartId=1|Location.X=95|Location.Y=710|Radius=3|SecondaryRadius=3|LineWidth=1|Color=16711680
|RECORD=13|OwnerIndex=43|IsNotAccesible=T|IndexInSheet=12|OwnerPartId=1|Location.X=98|Location.Y=710|Corner.X=120|Corner.Y=710|LineWidth=1|Color=16711680
|RECORD=8|OwnerIndex=43|IsNotAccesible=T|IndexInSheet=13|OwnerPartId=1|Location.X=95|Location.Y=690|Radius=3|SecondaryRadius=3|LineWidth=1|Color=16711680
|RECORD=13|OwnerIndex=43|IsNotAccesible=T|IndexInSheet=14|OwnerPartId=1|Location.X=98|Location.Y=690|Corner.X=120|Corner.Y=690|LineWidth=1|Color=16711680
|RECORD=8|OwnerIndex=43|IsNotAccesible=T|IndexInSheet=15|OwnerPartId=1|Location.X=95|Location.Y=670|Radius=3|SecondaryRadius=3|LineWidth=1|Color=16711680
|RECORD=13|OwnerIndex=43|IsNotAccesible=T|IndexInSheet=16|OwnerPartId=1|Location.X=98|Location.Y=670|Corner.X=120|Corner.Y=670|LineWidth=1|Color=16711680
|RECORD=8|OwnerIndex=43|IsNotAccesible=T|IndexInSheet=17|OwnerPartId=1|Location.X=95|Location.Y=650|Radius=3|SecondaryRadius=3|LineWidth=1|Color=16711680
|RECORD=13|OwnerIndex=43|IsNotAccesible=T|IndexInSheet=18|OwnerPartId=1|Location.X=98|Location.Y=650|Corner.X=120|Corner.Y=650|LineWidth=1|Color=16711680
|RECORD=8|OwnerIndex=43|IsNotAccesible=T|IndexInSheet=19|OwnerPartId=1|Location.X=95|Location.Y=630|Radius=3|SecondaryRadius=3|LineWidth=1|Color=16711680
|RECORD=13|OwnerIndex=43|IsNotAccesible=T|IndexInSheet=20|OwnerPartId=1|Location.X=98|Location.Y=630|Corner.X=120|Corner.Y=630|LineWidth=1|Color=16711680
|RECORD=8|OwnerIndex=43|IsNotAccesible=T|IndexInSheet=21|OwnerPartId=1|Location.X=95|Location.Y=610|Radius=3|SecondaryRadius=3|LineWidth=1|Color=16711680
|RECORD=13|OwnerIndex=43|IsNotAccesible=T|IndexInSheet=22|OwnerPartId=1|Location.X=98|Location.Y=610|Corner.X=120|Corner.Y=610|LineWidth=1|Color=16711680
|RECORD=8|OwnerIndex=43|IsNotAccesible=T|IndexInSheet=23|OwnerPartId=1|Location.X=95|Location.Y=590|Radius=3|SecondaryRadius=3|LineWidth=1|Color=16711680
|RECORD=13|OwnerIndex=43|IsNotAccesible=T|IndexInSheet=24|OwnerPartId=1|Location.X=98|Location.Y=590|Corner.X=120|Corner.Y=590|LineWidth=1|Color=16711680
|RECORD=8|OwnerIndex=43|IsNotAccesible=T|IndexInSheet=25|OwnerPartId=1|Location.X=95|Location.Y=570|Radius=3|SecondaryRadius=3|LineWidth=1|Color=16711680
|RECORD=13|OwnerIndex=43|IsNotAccesible=T|IndexInSheet=26|OwnerPartId=1|Location.X=98|Location.Y=570|Corner.X=120|Corner.Y=570|LineWidth=1|Color=16711680
|RECORD=8|OwnerIndex=43|IsNotAccesible=T|IndexInSheet=27|OwnerPartId=1|Location.X=95|Location.Y=550|Radius=3|SecondaryRadius=3|LineWidth=1|Color=16711680
|RECORD=13|OwnerIndex=43|IsNotAccesible=T|IndexInSheet=28|OwnerPartId=1|Location.X=98|Location.Y=550|Corner.X=120|Corner.Y=550|LineWidth=1|Color=16711680
|RECORD=8|OwnerIndex=43|IsNotAccesible=T|IndexInSheet=29|OwnerPartId=1|Location.X=95|Location.Y=530|Radius=3|SecondaryRadius=3|LineWidth=1|Color=16711680
|RECORD=13|OwnerIndex=43|IsNotAccesible=T|IndexInSheet=30|OwnerPartId=1|Location.X=98|Location.Y=530|Corner.X=120|Corner.Y=530|LineWidth=1|Color=16711680
|RECORD=8|OwnerIndex=43|IsNotAccesible=T|IndexInSheet=31|OwnerPartId=1|Location.X=95|Location.Y=510|Radius=3|SecondaryRadius=3|LineWidth=1|Color=16711680
|RECORD=13|OwnerIndex=43|IsNotAccesible=T|IndexInSheet=32|OwnerPartId=1|Location.X=98|Location.Y=510|Corner.X=120|Corner.Y=510|LineWidth=1|Color=16711680
|RECORD=8|OwnerIndex=43|IsNotAccesible=T|IndexInSheet=33|OwnerPartId=1|Location.X=95|Location.Y=490|Radius=3|SecondaryRadius=3|LineWidth=1|Color=16711680
|RECORD=13|OwnerIndex=43|IsNotAccesible=T|IndexInSheet=34|OwnerPartId=1|Location.X=98|Location.Y=490|Corner.X=120|Corner.Y=490|LineWidth=1|Color=16711680
|RECORD=8|OwnerIndex=43|IsNotAccesible=T|IndexInSheet=35|OwnerPartId=1|Location.X=95|Location.Y=470|Radius=3|SecondaryRadius=3|LineWidth=1|Color=16711680
|RECORD=13|OwnerIndex=43|IsNotAccesible=T|IndexInSheet=36|OwnerPartId=1|Location.X=98|Location.Y=470|Corner.X=120|Corner.Y=470|LineWidth=1|Color=16711680
|RECORD=8|OwnerIndex=43|IsNotAccesible=T|IndexInSheet=37|OwnerPartId=1|Location.X=95|Location.Y=450|Radius=3|SecondaryRadius=3|LineWidth=1|Color=16711680
|RECORD=13|OwnerIndex=43|IsNotAccesible=T|IndexInSheet=38|OwnerPartId=1|Location.X=98|Location.Y=450|Corner.X=120|Corner.Y=450|LineWidth=1|Color=16711680
|RECORD=8|OwnerIndex=43|IsNotAccesible=T|IndexInSheet=39|OwnerPartId=1|Location.X=95|Location.Y=430|Radius=3|SecondaryRadius=3|LineWidth=1|Color=16711680
|RECORD=13|OwnerIndex=43|IsNotAccesible=T|IndexInSheet=40|OwnerPartId=1|Location.X=98|Location.Y=430|Corner.X=120|Corner.Y=430|LineWidth=1|Color=16711680
|RECORD=8|OwnerIndex=43|IsNotAccesible=T|IndexInSheet=41|OwnerPartId=1|Location.X=95|Location.Y=410|Radius=3|SecondaryRadius=3|LineWidth=1|Color=16711680
|RECORD=13|OwnerIndex=43|IsNotAccesible=T|IndexInSheet=42|OwnerPartId=1|Location.X=98|Location.Y=410|Corner.X=120|Corner.Y=410|LineWidth=1|Color=16711680
|RECORD=8|OwnerIndex=43|IsNotAccesible=T|IndexInSheet=43|OwnerPartId=1|Location.X=95|Location.Y=390|Radius=3|SecondaryRadius=3|LineWidth=1|Color=16711680
|RECORD=13|OwnerIndex=43|IsNotAccesible=T|IndexInSheet=44|OwnerPartId=1|Location.X=98|Location.Y=390|Corner.X=120|Corner.Y=390|LineWidth=1|Color=16711680
|RECORD=8|OwnerIndex=43|IsNotAccesible=T|IndexInSheet=45|OwnerPartId=1|Location.X=95|Location.Y=370|Radius=3|SecondaryRadius=3|LineWidth=1|Color=16711680
|RECORD=13|OwnerIndex=43|IsNotAccesible=T|IndexInSheet=46|OwnerPartId=1|Location.X=98|Location.Y=370|Corner.X=120|Corner.Y=370|LineWidth=1|Color=16711680
|RECORD=8|OwnerIndex=43|IsNotAccesible=T|IndexInSheet=47|OwnerPartId=1|Location.X=95|Location.Y=350|Radius=3|SecondaryRadius=3|LineWidth=1|Color=16711680
|RECORD=13|OwnerIndex=43|IsNotAccesible=T|IndexInSheet=48|OwnerPartId=1|Location.X=98|Location.Y=350|Corner.X=120|Corner.Y=350|LineWidth=1|Color=16711680
|RECORD=8|OwnerIndex=43|IsNotAccesible=T|IndexInSheet=49|OwnerPartId=1|Location.X=95|Location.Y=330|Radius=3|SecondaryRadius=3|LineWidth=1|Color=16711680
|RECORD=13|OwnerIndex=43|IsNotAccesible=T|IndexInSheet=50|OwnerPartId=1|Location.X=98|Location.Y=330|Corner.X=120|Corner.Y=330|LineWidth=1|Color=16711680
|RECORD=8|OwnerIndex=43|IsNotAccesible=T|IndexInSheet=51|OwnerPartId=1|Location.X=95|Location.Y=310|Radius=3|SecondaryRadius=3|LineWidth=1|Color=16711680
|RECORD=13|OwnerIndex=43|IsNotAccesible=T|IndexInSheet=52|OwnerPartId=1|Location.X=98|Location.Y=310|Corner.X=120|Corner.Y=310|LineWidth=1|Color=16711680
|RECORD=8|OwnerIndex=43|IsNotAccesible=T|IndexInSheet=53|OwnerPartId=1|Location.X=95|Location.Y=290|Radius=3|SecondaryRadius=3|LineWidth=1|Color=16711680
|RECORD=13|OwnerIndex=43|IsNotAccesible=T|IndexInSheet=54|OwnerPartId=1|Location.X=98|Location.Y=290|Corner.X=120|Corner.Y=290|LineWidth=1|Color=16711680
|RECORD=8|OwnerIndex=43|IsNotAccesible=T|IndexInSheet=55|OwnerPartId=1|Location.X=95|Location.Y=270|Radius=3|SecondaryRadius=3|LineWidth=1|Color=16711680
|RECORD=13|OwnerIndex=43|IsNotAccesible=T|IndexInSheet=56|OwnerPartId=1|Location.X=98|Location.Y=270|Corner.X=120|Corner.Y=270|LineWidth=1|Color=16711680
|RECORD=8|OwnerIndex=43|IsNotAccesible=T|IndexInSheet=57|OwnerPartId=1|Location.X=95|Location.Y=250|Radius=3|SecondaryRadius=3|LineWidth=1|Color=16711680
|RECORD=13|OwnerIndex=43|IsNotAccesible=T|IndexInSheet=58|OwnerPartId=1|Location.X=98|Location.Y=250|Corner.X=120|Corner.Y=250|LineWidth=1|Color=16711680
|RECORD=8|OwnerIndex=43|IsNotAccesible=T|IndexInSheet=59|OwnerPartId=1|Location.X=95|Location.Y=230|Radius=3|SecondaryRadius=3|LineWidth=1|Color=16711680
|RECORD=13|OwnerIndex=43|IsNotAccesible=T|IndexInSheet=60|OwnerPartId=1|Location.X=98|Location.Y=230|Corner.X=120|Corner.Y=230|LineWidth=1|Color=16711680
|RECORD=8|OwnerIndex=43|IsNotAccesible=T|IndexInSheet=61|OwnerPartId=1|Location.X=95|Location.Y=210|Radius=3|SecondaryRadius=3|LineWidth=1|Color=16711680
|RECORD=13|OwnerIndex=43|IsNotAccesible=T|IndexInSheet=62|OwnerPartId=1|Location.X=98|Location.Y=210|Corner.X=120|Corner.Y=210|LineWidth=1|Color=16711680
|RECORD=8|OwnerIndex=43|IsNotAccesible=T|IndexInSheet=63|OwnerPartId=1|Location.X=95|Location.Y=190|Radius=3|SecondaryRadius=3|LineWidth=1|Color=16711680
|RECORD=13|OwnerIndex=43|IsNotAccesible=T|IndexInSheet=64|OwnerPartId=1|Location.X=98|Location.Y=190|Corner.X=120|Corner.Y=190|LineWidth=1|Color=16711680
|RECORD=8|OwnerIndex=43|IsNotAccesible=T|IndexInSheet=65|OwnerPartId=1|Location.X=95|Location.Y=170|Radius=3|SecondaryRadius=3|LineWidth=1|Color=16711680
|RECORD=13|OwnerIndex=43|IsNotAccesible=T|IndexInSheet=66|OwnerPartId=1|Location.X=98|Location.Y=170|Corner.X=120|Corner.Y=170|LineWidth=1|Color=16711680
|RECORD=8|OwnerIndex=43|IsNotAccesible=T|IndexInSheet=67|OwnerPartId=1|Location.X=95|Location.Y=150|Radius=3|SecondaryRadius=3|LineWidth=1|Color=16711680
|RECORD=13|OwnerIndex=43|IsNotAccesible=T|IndexInSheet=68|OwnerPartId=1|Location.X=98|Location.Y=150|Corner.X=120|Corner.Y=150|LineWidth=1|Color=16711680
|RECORD=8|OwnerIndex=43|IsNotAccesible=T|IndexInSheet=69|OwnerPartId=1|Location.X=95|Location.Y=130|Radius=3|SecondaryRadius=3|LineWidth=1|Color=16711680
|RECORD=13|OwnerIndex=43|IsNotAccesible=T|IndexInSheet=70|OwnerPartId=1|Location.X=98|Location.Y=130|Corner.X=120|Corner.Y=130|LineWidth=1|Color=16711680
|RECORD=4|OwnerIndex=43|IsNotAccesible=T|IndexInSheet=71|OwnerPartId=1|Location.X=113|Location.Y=822|Justification=8|Color=8388608|FontID=1|Text=1
|RECORD=4|OwnerIndex=43|IsNotAccesible=T|IndexInSheet=72|OwnerPartId=1|Location.X=113|Location.Y=802|Justification=8|Color=8388608|FontID=1|Text=3
|RECORD=4|OwnerIndex=43|IsNotAccesible=T|IndexInSheet=73|OwnerPartId=1|Location.X=113|Location.Y=782|Justification=8|Color=8388608|FontID=1|Text=5
|RECORD=4|OwnerIndex=43|IsNotAccesible=T|IndexInSheet=74|OwnerPartId=1|Location.X=113|Location.Y=762|Justification=8|Color=8388608|FontID=1|Text=7
|RECORD=4|OwnerIndex=43|IsNotAccesible=T|IndexInSheet=75|OwnerPartId=1|Location.X=113|Location.Y=742|Justification=8|Color=8388608|FontID=1|Text=9
|RECORD=4|OwnerIndex=43|IsNotAccesible=T|IndexInSheet=76|OwnerPartId=1|Location.X=113|Location.Y=722|Justification=8|Color=8388608|FontID=1|Text=11
|RECORD=4|OwnerIndex=43|IsNotAccesible=T|IndexInSheet=77|OwnerPartId=1|Location.X=113|Location.Y=702|Justification=8|Color=8388608|FontID=1|Text=21
|RECORD=4|OwnerIndex=43|IsNotAccesible=T|IndexInSheet=78|OwnerPartId=1|Location.X=113|Location.Y=682|Justification=8|Color=8388608|FontID=1|Text=23
|RECORD=4|OwnerIndex=43|IsNotAccesible=T|IndexInSheet=79|OwnerPartId=1|Location.X=113|Location.Y=662|Justification=8|Color=8388608|FontID=1|Text=25
|RECORD=4|OwnerIndex=43|IsNotAccesible=T|IndexInSheet=80|OwnerPartId=1|Location.X=113|Location.Y=642|Justification=8|Color=8388608|FontID=1|Text=27
|RECORD=4|OwnerIndex=43|IsNotAccesible=T|IndexInSheet=81|OwnerPartId=1|Location.X=113|Location.Y=622|Justification=8|Color=8388608|FontID=1|Text=29
|RECORD=4|OwnerIndex=43|IsNotAccesible=T|IndexInSheet=82|OwnerPartId=1|Location.X=113|Location.Y=602|Justification=8|Color=8388608|FontID=1|Text=31
|RECORD=4|OwnerIndex=43|IsNotAccesible=T|IndexInSheet=83|OwnerPartId=1|Location.X=113|Location.Y=582|Justification=8|Color=8388608|FontID=1|Text=33
|RECORD=4|OwnerIndex=43|IsNotAccesible=T|IndexInSheet=84|OwnerPartId=1|Location.X=113|Location.Y=562|Justification=8|Color=8388608|FontID=1|Text=35
|RECORD=4|OwnerIndex=43|IsNotAccesible=T|IndexInSheet=85|OwnerPartId=1|Location.X=113|Location.Y=542|Justification=8|Color=8388608|FontID=1|Text=37
|RECORD=4|OwnerIndex=43|IsNotAccesible=T|IndexInSheet=86|OwnerPartId=1|Location.X=113|Location.Y=522|Justification=8|Color=8388608|FontID=1|Text=39
|RECORD=4|OwnerIndex=43|IsNotAccesible=T|IndexInSheet=87|OwnerPartId=1|Location.X=113|Location.Y=502|Justification=8|Color=8388608|FontID=1|Text=41
|RECORD=4|OwnerIndex=43|IsNotAccesible=T|IndexInSheet=88|OwnerPartId=1|Location.X=113|Location.Y=482|Justification=8|Color=8388608|FontID=1|Text=43
|RECORD=4|OwnerIndex=43|IsNotAccesible=T|IndexInSheet=89|OwnerPartId=1|Location.X=113|Location.Y=462|Justification=8|Color=8388608|FontID=1|Text=45
|RECORD=4|OwnerIndex=43|IsNotAccesible=T|IndexInSheet=90|OwnerPartId=1|Location.X=113|Location.Y=442|Justification=8|Color=8388608|FontID=1|Text=47
|RECORD=4|OwnerIndex=43|IsNotAccesible=T|IndexInSheet=91|OwnerPartId=1|Location.X=113|Location.Y=422|Justification=8|Color=8388608|FontID=1|Text=49
|RECORD=4|OwnerIndex=43|IsNotAccesible=T|IndexInSheet=92|OwnerPartId=1|Location.X=113|Location.Y=402|Justification=8|Color=8388608|FontID=1|Text=51
|RECORD=4|OwnerIndex=43|IsNotAccesible=T|IndexInSheet=93|OwnerPartId=1|Location.X=113|Location.Y=382|Justification=8|Color=8388608|FontID=1|Text=53
|RECORD=4|OwnerIndex=43|IsNotAccesible=T|IndexInSheet=94|OwnerPartId=1|Location.X=113|Location.Y=362|Justification=8|Color=8388608|FontID=1|Text=55
|RECORD=4|OwnerIndex=43|IsNotAccesible=T|IndexInSheet=95|OwnerPartId=1|Location.X=113|Location.Y=342|Justification=8|Color=8388608|FontID=1|Text=57
|RECORD=4|OwnerIndex=43|IsNotAccesible=T|IndexInSheet=96|OwnerPartId=1|Location.X=113|Location.Y=322|Justification=8|Color=8388608|FontID=1|Text=59
|RECORD=4|OwnerIndex=43|IsNotAccesible=T|IndexInSheet=97|OwnerPartId=1|Location.X=113|Location.Y=302|Justification=8|Color=8388608|FontID=1|Text=61
|RECORD=4|OwnerIndex=43|IsNotAccesible=T|IndexInSheet=98|OwnerPartId=1|Location.X=113|Location.Y=282|Justification=8|Color=8388608|FontID=1|Text=63
|RECORD=4|OwnerIndex=43|IsNotAccesible=T|IndexInSheet=99|OwnerPartId=1|Location.X=113|Location.Y=262|Justification=8|Color=8388608|FontID=1|Text=65
|RECORD=4|OwnerIndex=43|IsNotAccesible=T|IndexInSheet=100|OwnerPartId=1|Location.X=113|Location.Y=242|Justification=8|Color=8388608|FontID=1|Text=67
|RECORD=4|OwnerIndex=43|IsNotAccesible=T|IndexInSheet=101|OwnerPartId=1|Location.X=113|Location.Y=222|Justification=8|Color=8388608|FontID=1|Text=69
|RECORD=4|OwnerIndex=43|IsNotAccesible=T|IndexInSheet=102|OwnerPartId=1|Location.X=113|Location.Y=202|Justification=8|Color=8388608|FontID=1|Text=71
|RECORD=4|OwnerIndex=43|IsNotAccesible=T|IndexInSheet=103|OwnerPartId=1|Location.X=113|Location.Y=182|Justification=8|Color=8388608|FontID=1|Text=73
|RECORD=4|OwnerIndex=43|IsNotAccesible=T|IndexInSheet=104|OwnerPartId=1|Location.X=113|Location.Y=162|Justification=8|Color=8388608|FontID=1|Text=75
|RECORD=4|OwnerIndex=43|IsNotAccesible=T|IndexInSheet=105|OwnerPartId=1|Location.X=113|Location.Y=142|Justification=8|Color=8388608|FontID=1|Text=MNT 2
|RECORD=2|OwnerIndex=43|OwnerPartId=1|Electrical=4|PinConglomerate=48|PinLength=20|Location.X=120|Location.Y=810|Name=1|Designator=1|PinName_PositionConglomerate=16|Name_CustomFontID=1|PinDesignator_PositionConglomerate=16|Designator_CustomFontID=1|PinPropagationDelay=0.000000E+000
|RECORD=2|OwnerIndex=43|OwnerPartId=1|Electrical=4|PinConglomerate=48|PinLength=20|Location.X=120|Location.Y=790|Name=3|Designator=3|PinName_PositionConglomerate=16|Name_CustomFontID=1|PinDesignator_PositionConglomerate=16|Designator_CustomFontID=1|PinPropagationDelay=0.000000E+000
|RECORD=2|OwnerIndex=43|OwnerPartId=1|Electrical=4|PinConglomerate=48|PinLength=20|Location.X=120|Location.Y=770|Name=5|Designator=5|PinName_PositionConglomerate=16|Name_CustomFontID=1|PinDesignator_PositionConglomerate=16|Designator_CustomFontID=1|PinPropagationDelay=0.000000E+000
|RECORD=2|OwnerIndex=43|OwnerPartId=1|Electrical=4|PinConglomerate=48|PinLength=20|Location.X=120|Location.Y=750|Name=7|Designator=7|PinName_PositionConglomerate=16|Name_CustomFontID=1|PinDesignator_PositionConglomerate=16|Designator_CustomFontID=1|PinPropagationDelay=0.000000E+000
|RECORD=2|OwnerIndex=43|OwnerPartId=1|Electrical=4|PinConglomerate=48|PinLength=20|Location.X=120|Location.Y=730|Name=9|Designator=9|PinName_PositionConglomerate=16|Name_CustomFontID=1|PinDesignator_PositionConglomerate=16|Designator_CustomFontID=1|PinPropagationDelay=0.000000E+000
|RECORD=2|OwnerIndex=43|OwnerPartId=1|Electrical=4|PinConglomerate=48|PinLength=20|Location.X=120|Location.Y=710|Name=11|Designator=11|PinName_PositionConglomerate=16|Name_CustomFontID=1|PinDesignator_PositionConglomerate=16|Designator_CustomFontID=1|PinPropagationDelay=0.000000E+000
|RECORD=2|OwnerIndex=43|OwnerPartId=1|Electrical=4|PinConglomerate=48|PinLength=20|Location.X=120|Location.Y=690|Name=21|Designator=21|PinName_PositionConglomerate=16|Name_CustomFontID=1|PinDesignator_PositionConglomerate=16|Designator_CustomFontID=1|PinPropagationDelay=0.000000E+000
|RECORD=2|OwnerIndex=43|OwnerPartId=1|Electrical=4|PinConglomerate=48|PinLength=20|Location.X=120|Location.Y=670|Name=23|Designator=23|PinName_PositionConglomerate=16|Name_CustomFontID=1|PinDesignator_PositionConglomerate=16|Designator_CustomFontID=1|PinPropagationDelay=0.000000E+000
|RECORD=2|OwnerIndex=43|OwnerPartId=1|Electrical=4|PinConglomerate=48|PinLength=20|Location.X=120|Location.Y=650|Name=25|Designator=25|PinName_PositionConglomerate=16|Name_CustomFontID=1|PinDesignator_PositionConglomerate=16|Designator_CustomFontID=1|PinPropagationDelay=0.000000E+000
|RECORD=2|OwnerIndex=43|OwnerPartId=1|Electrical=4|PinConglomerate=48|PinLength=20|Location.X=120|Location.Y=630|Name=27|Designator=27|PinName_PositionConglomerate=16|Name_CustomFontID=1|PinDesignator_PositionConglomerate=16|Designator_CustomFontID=1|PinPropagationDelay=0.000000E+000
|RECORD=2|OwnerIndex=43|OwnerPartId=1|Electrical=4|PinConglomerate=48|PinLength=20|Location.X=120|Location.Y=610|Name=29|Designator=29|PinName_PositionConglomerate=16|Name_CustomFontID=1|PinDesignator_PositionConglomerate=16|Designator_CustomFontID=1|PinPropagationDelay=0.000000E+000
|RECORD=2|OwnerIndex=43|OwnerPartId=1|Electrical=4|PinConglomerate=48|PinLength=20|Location.X=120|Location.Y=590|Name=31|Designator=31|PinName_PositionConglomerate=16|Name_CustomFontID=1|PinDesignator_PositionConglomerate=16|Designator_CustomFontID=1|PinPropagationDelay=0.000000E+000
|RECORD=2|OwnerIndex=43|OwnerPartId=1|Electrical=4|PinConglomerate=48|PinLength=20|Location.X=120|Location.Y=570|Name=33|Designator=33|PinName_PositionConglomerate=16|Name_CustomFontID=1|PinDesignator_PositionConglomerate=16|Designator_CustomFontID=1|PinPropagationDelay=0.000000E+000
|RECORD=2|OwnerIndex=43|OwnerPartId=1|Electrical=4|PinConglomerate=48|PinLength=20|Location.X=120|Location.Y=550|Name=35|Designator=35|PinName_PositionConglomerate=16|Name_CustomFontID=1|PinDesignator_PositionConglomerate=16|Designator_CustomFontID=1|PinPropagationDelay=0.000000E+000
|RECORD=2|OwnerIndex=43|OwnerPartId=1|Electrical=4|PinConglomerate=48|PinLength=20|Location.X=120|Location.Y=530|Name=37|Designator=37|PinName_PositionConglomerate=16|Name_CustomFontID=1|PinDesignator_PositionConglomerate=16|Designator_CustomFontID=1|PinPropagationDelay=0.000000E+000
|RECORD=2|OwnerIndex=43|OwnerPartId=1|Electrical=4|PinConglomerate=48|PinLength=20|Location.X=120|Location.Y=510|Name=39|Designator=39|PinName_PositionConglomerate=16|Name_CustomFontID=1|PinDesignator_PositionConglomerate=16|Designator_CustomFontID=1|PinPropagationDelay=0.000000E+000
|RECORD=2|OwnerIndex=43|OwnerPartId=1|Electrical=4|PinConglomerate=48|PinLength=20|Location.X=120|Location.Y=490|Name=41|Designator=41|PinName_PositionConglomerate=16|Name_CustomFontID=1|PinDesignator_PositionConglomerate=16|Designator_CustomFontID=1|PinPropagationDelay=0.000000E+000
|RECORD=2|OwnerIndex=43|OwnerPartId=1|Electrical=4|PinConglomerate=48|PinLength=20|Location.X=120|Location.Y=470|Name=43|Designator=43|PinName_PositionConglomerate=16|Name_CustomFontID=1|PinDesignator_PositionConglomerate=16|Designator_CustomFontID=1|PinPropagationDelay=0.000000E+000
|RECORD=2|OwnerIndex=43|OwnerPartId=1|Electrical=4|PinConglomerate=48|PinLength=20|Location.X=120|Location.Y=450|Name=45|Designator=45|PinName_PositionConglomerate=16|Name_CustomFontID=1|PinDesignator_PositionConglomerate=16|Designator_CustomFontID=1|PinPropagationDelay=0.000000E+000
|RECORD=2|OwnerIndex=43|OwnerPartId=1|Electrical=4|PinConglomerate=48|PinLength=20|Location.X=120|Location.Y=430|Name=47|Designator=47|PinName_PositionConglomerate=16|Name_CustomFontID=1|PinDesignator_PositionConglomerate=16|Designator_CustomFontID=1|PinPropagationDelay=0.000000E+000
|RECORD=2|OwnerIndex=43|OwnerPartId=1|Electrical=4|PinConglomerate=48|PinLength=20|Location.X=120|Location.Y=410|Name=49|Designator=49|PinName_PositionConglomerate=16|Name_CustomFontID=1|PinDesignator_PositionConglomerate=16|Designator_CustomFontID=1|PinPropagationDelay=0.000000E+000
|RECORD=2|OwnerIndex=43|OwnerPartId=1|Electrical=4|PinConglomerate=48|PinLength=20|Location.X=120|Location.Y=390|Name=51|Designator=51|PinName_PositionConglomerate=16|Name_CustomFontID=1|PinDesignator_PositionConglomerate=16|Designator_CustomFontID=1|PinPropagationDelay=0.000000E+000
|RECORD=2|OwnerIndex=43|OwnerPartId=1|Electrical=4|PinConglomerate=48|PinLength=20|Location.X=120|Location.Y=370|Name=53|Designator=53|PinName_PositionConglomerate=16|Name_CustomFontID=1|PinDesignator_PositionConglomerate=16|Designator_CustomFontID=1|PinPropagationDelay=0.000000E+000
|RECORD=2|OwnerIndex=43|OwnerPartId=1|Electrical=4|PinConglomerate=48|PinLength=20|Location.X=120|Location.Y=350|Name=55|Designator=55|PinName_PositionConglomerate=16|Name_CustomFontID=1|PinDesignator_PositionConglomerate=16|Designator_CustomFontID=1|PinPropagationDelay=0.000000E+000
|RECORD=2|OwnerIndex=43|OwnerPartId=1|Electrical=4|PinConglomerate=48|PinLength=20|Location.X=120|Location.Y=330|Name=57|Designator=57|PinName_PositionConglomerate=16|Name_CustomFontID=1|PinDesignator_PositionConglomerate=16|Designator_CustomFontID=1|PinPropagationDelay=0.000000E+000
|RECORD=2|OwnerIndex=43|OwnerPartId=1|Electrical=4|PinConglomerate=48|PinLength=20|Location.X=120|Location.Y=310|Name=59|Designator=59|PinName_PositionConglomerate=16|Name_CustomFontID=1|PinDesignator_PositionConglomerate=16|Designator_CustomFontID=1|PinPropagationDelay=0.000000E+000
|RECORD=2|OwnerIndex=43|OwnerPartId=1|Electrical=4|PinConglomerate=48|PinLength=20|Location.X=120|Location.Y=290|Name=61|Designator=61|PinName_PositionConglomerate=16|Name_CustomFontID=1|PinDesignator_PositionConglomerate=16|Designator_CustomFontID=1|PinPropagationDelay=0.000000E+000
|RECORD=2|OwnerIndex=43|OwnerPartId=1|Electrical=4|PinConglomerate=48|PinLength=20|Location.X=120|Location.Y=270|Name=63|Designator=63|PinName_PositionConglomerate=16|Name_CustomFontID=1|PinDesignator_PositionConglomerate=16|Designator_CustomFontID=1|PinPropagationDelay=0.000000E+000
|RECORD=2|OwnerIndex=43|OwnerPartId=1|Electrical=4|PinConglomerate=48|PinLength=20|Location.X=120|Location.Y=250|Name=65|Designator=65|PinName_PositionConglomerate=16|Name_CustomFontID=1|PinDesignator_PositionConglomerate=16|Designator_CustomFontID=1|PinPropagationDelay=0.000000E+000
|RECORD=2|OwnerIndex=43|OwnerPartId=1|Electrical=4|PinConglomerate=48|PinLength=20|Location.X=120|Location.Y=230|Name=67|Designator=67|PinName_PositionConglomerate=16|Name_CustomFontID=1|PinDesignator_PositionConglomerate=16|Designator_CustomFontID=1|PinPropagationDelay=0.000000E+000
|RECORD=2|OwnerIndex=43|OwnerPartId=1|Electrical=4|PinConglomerate=48|PinLength=20|Location.X=120|Location.Y=210|Name=69|Designator=69|PinName_PositionConglomerate=16|Name_CustomFontID=1|PinDesignator_PositionConglomerate=16|Designator_CustomFontID=1|PinPropagationDelay=0.000000E+000
|RECORD=2|OwnerIndex=43|OwnerPartId=1|Electrical=4|PinConglomerate=48|PinLength=20|Location.X=120|Location.Y=190|Name=71|Designator=71|PinName_PositionConglomerate=16|Name_CustomFontID=1|PinDesignator_PositionConglomerate=16|Designator_CustomFontID=1|PinPropagationDelay=0.000000E+000
|RECORD=2|OwnerIndex=43|OwnerPartId=1|Electrical=4|PinConglomerate=48|PinLength=20|Location.X=120|Location.Y=170|Name=73|Designator=73|PinName_PositionConglomerate=16|Name_CustomFontID=1|PinDesignator_PositionConglomerate=16|Designator_CustomFontID=1|PinPropagationDelay=0.000000E+000
|RECORD=2|OwnerIndex=43|OwnerPartId=1|Electrical=4|PinConglomerate=48|PinLength=20|Location.X=120|Location.Y=150|Name=75|Designator=75|PinName_PositionConglomerate=16|Name_CustomFontID=1|PinDesignator_PositionConglomerate=16|Designator_CustomFontID=1|PinPropagationDelay=0.000000E+000
|RECORD=2|OwnerIndex=43|OwnerPartId=1|Electrical=4|PinConglomerate=48|PinLength=20|Location.X=120|Location.Y=130|Name=MNT 2|Designator=77|PinName_PositionConglomerate=16|Name_CustomFontID=1|PinDesignator_PositionConglomerate=16|Designator_CustomFontID=1|PinPropagationDelay=0.000000E+000
|RECORD=14|OwnerIndex=43|IsNotAccesible=T|IndexInSheet=141|OwnerPartId=2|Location.X=70|Location.Y=130|Corner.X=120|Corner.Y=830|LineWidth=1|Color=128|AreaColor=11599871|IsSolid=T
|RECORD=8|OwnerIndex=43|IsNotAccesible=T|IndexInSheet=142|OwnerPartId=2|Location.X=95|Location.Y=810|Radius=3|SecondaryRadius=3|LineWidth=1|Color=16711680
|RECORD=13|OwnerIndex=43|IsNotAccesible=T|IndexInSheet=143|OwnerPartId=2|Location.X=98|Location.Y=810|Corner.X=120|Corner.Y=810|LineWidth=1|Color=16711680
|RECORD=8|OwnerIndex=43|IsNotAccesible=T|IndexInSheet=144|OwnerPartId=2|Location.X=95|Location.Y=790|Radius=3|SecondaryRadius=3|LineWidth=1|Color=16711680
|RECORD=13|OwnerIndex=43|IsNotAccesible=T|IndexInSheet=145|OwnerPartId=2|Location.X=98|Location.Y=790|Corner.X=120|Corner.Y=790|LineWidth=1|Color=16711680
|RECORD=8|OwnerIndex=43|IsNotAccesible=T|IndexInSheet=146|OwnerPartId=2|Location.X=95|Location.Y=770|Radius=3|SecondaryRadius=3|LineWidth=1|Color=16711680
|RECORD=13|OwnerIndex=43|IsNotAccesible=T|IndexInSheet=147|OwnerPartId=2|Location.X=98|Location.Y=770|Corner.X=120|Corner.Y=770|LineWidth=1|Color=16711680
|RECORD=8|OwnerIndex=43|IsNotAccesible=T|IndexInSheet=148|OwnerPartId=2|Location.X=95|Location.Y=750|Radius=3|SecondaryRadius=3|LineWidth=1|Color=16711680
|RECORD=13|OwnerIndex=43|IsNotAccesible=T|IndexInSheet=149|OwnerPartId=2|Location.X=98|Location.Y=750|Corner.X=120|Corner.Y=750|LineWidth=1|Color=16711680
|RECORD=8|OwnerIndex=43|IsNotAccesible=T|IndexInSheet=150|OwnerPartId=2|Location.X=95|Location.Y=730|Radius=3|SecondaryRadius=3|LineWidth=1|Color=16711680
|RECORD=13|OwnerIndex=43|IsNotAccesible=T|IndexInSheet=151|OwnerPartId=2|Location.X=98|Location.Y=730|Corner.X=120|Corner.Y=730|LineWidth=1|Color=16711680
|RECORD=8|OwnerIndex=43|IsNotAccesible=T|IndexInSheet=152|OwnerPartId=2|Location.X=95|Location.Y=710|Radius=3|SecondaryRadius=3|LineWidth=1|Color=16711680
|RECORD=13|OwnerIndex=43|IsNotAccesible=T|IndexInSheet=153|OwnerPartId=2|Location.X=98|Location.Y=710|Corner.X=120|Corner.Y=710|LineWidth=1|Color=16711680
|RECORD=8|OwnerIndex=43|IsNotAccesible=T|IndexInSheet=154|OwnerPartId=2|Location.X=95|Location.Y=690|Radius=3|SecondaryRadius=3|LineWidth=1|Color=16711680
|RECORD=13|OwnerIndex=43|IsNotAccesible=T|IndexInSheet=155|OwnerPartId=2|Location.X=98|Location.Y=690|Corner.X=120|Corner.Y=690|LineWidth=1|Color=16711680
|RECORD=8|OwnerIndex=43|IsNotAccesible=T|IndexInSheet=156|OwnerPartId=2|Location.X=95|Location.Y=670|Radius=3|SecondaryRadius=3|LineWidth=1|Color=16711680
|RECORD=13|OwnerIndex=43|IsNotAccesible=T|IndexInSheet=157|OwnerPartId=2|Location.X=98|Location.Y=670|Corner.X=120|Corner.Y=670|LineWidth=1|Color=16711680
|RECORD=8|OwnerIndex=43|IsNotAccesible=T|IndexInSheet=158|OwnerPartId=2|Location.X=95|Location.Y=650|Radius=3|SecondaryRadius=3|LineWidth=1|Color=16711680
|RECORD=13|OwnerIndex=43|IsNotAccesible=T|IndexInSheet=159|OwnerPartId=2|Location.X=98|Location.Y=650|Corner.X=120|Corner.Y=650|LineWidth=1|Color=16711680
|RECORD=8|OwnerIndex=43|IsNotAccesible=T|IndexInSheet=160|OwnerPartId=2|Location.X=95|Location.Y=630|Radius=3|SecondaryRadius=3|LineWidth=1|Color=16711680
|RECORD=13|OwnerIndex=43|IsNotAccesible=T|IndexInSheet=161|OwnerPartId=2|Location.X=98|Location.Y=630|Corner.X=120|Corner.Y=630|LineWidth=1|Color=16711680
|RECORD=8|OwnerIndex=43|IsNotAccesible=T|IndexInSheet=162|OwnerPartId=2|Location.X=95|Location.Y=610|Radius=3|SecondaryRadius=3|LineWidth=1|Color=16711680
|RECORD=13|OwnerIndex=43|IsNotAccesible=T|IndexInSheet=163|OwnerPartId=2|Location.X=98|Location.Y=610|Corner.X=120|Corner.Y=610|LineWidth=1|Color=16711680
|RECORD=8|OwnerIndex=43|IsNotAccesible=T|IndexInSheet=164|OwnerPartId=2|Location.X=95|Location.Y=590|Radius=3|SecondaryRadius=3|LineWidth=1|Color=16711680
|RECORD=13|OwnerIndex=43|IsNotAccesible=T|IndexInSheet=165|OwnerPartId=2|Location.X=98|Location.Y=590|Corner.X=120|Corner.Y=590|LineWidth=1|Color=16711680
|RECORD=8|OwnerIndex=43|IsNotAccesible=T|IndexInSheet=166|OwnerPartId=2|Location.X=95|Location.Y=570|Radius=3|SecondaryRadius=3|LineWidth=1|Color=16711680
|RECORD=13|OwnerIndex=43|IsNotAccesible=T|IndexInSheet=167|OwnerPartId=2|Location.X=98|Location.Y=570|Corner.X=120|Corner.Y=570|LineWidth=1|Color=16711680
|RECORD=8|OwnerIndex=43|IsNotAccesible=T|IndexInSheet=168|OwnerPartId=2|Location.X=95|Location.Y=550|Radius=3|SecondaryRadius=3|LineWidth=1|Color=16711680
|RECORD=13|OwnerIndex=43|IsNotAccesible=T|IndexInSheet=169|OwnerPartId=2|Location.X=98|Location.Y=550|Corner.X=120|Corner.Y=550|LineWidth=1|Color=16711680
|RECORD=8|OwnerIndex=43|IsNotAccesible=T|IndexInSheet=170|OwnerPartId=2|Location.X=95|Location.Y=530|Radius=3|SecondaryRadius=3|LineWidth=1|Color=16711680
|RECORD=13|OwnerIndex=43|IsNotAccesible=T|IndexInSheet=171|OwnerPartId=2|Location.X=98|Location.Y=530|Corner.X=120|Corner.Y=530|LineWidth=1|Color=16711680
|RECORD=8|OwnerIndex=43|IsNotAccesible=T|IndexInSheet=172|OwnerPartId=2|Location.X=95|Location.Y=510|Radius=3|SecondaryRadius=3|LineWidth=1|Color=16711680
|RECORD=13|OwnerIndex=43|IsNotAccesible=T|IndexInSheet=173|OwnerPartId=2|Location.X=98|Location.Y=510|Corner.X=120|Corner.Y=510|LineWidth=1|Color=16711680
|RECORD=8|OwnerIndex=43|IsNotAccesible=T|IndexInSheet=174|OwnerPartId=2|Location.X=95|Location.Y=490|Radius=3|SecondaryRadius=3|LineWidth=1|Color=16711680
|RECORD=13|OwnerIndex=43|IsNotAccesible=T|IndexInSheet=175|OwnerPartId=2|Location.X=98|Location.Y=490|Corner.X=120|Corner.Y=490|LineWidth=1|Color=16711680
|RECORD=8|OwnerIndex=43|IsNotAccesible=T|IndexInSheet=176|OwnerPartId=2|Location.X=95|Location.Y=470|Radius=3|SecondaryRadius=3|LineWidth=1|Color=16711680
|RECORD=13|OwnerIndex=43|IsNotAccesible=T|IndexInSheet=177|OwnerPartId=2|Location.X=98|Location.Y=470|Corner.X=120|Corner.Y=470|LineWidth=1|Color=16711680
|RECORD=8|OwnerIndex=43|IsNotAccesible=T|IndexInSheet=178|OwnerPartId=2|Location.X=95|Location.Y=450|Radius=3|SecondaryRadius=3|LineWidth=1|Color=16711680
|RECORD=13|OwnerIndex=43|IsNotAccesible=T|IndexInSheet=179|OwnerPartId=2|Location.X=98|Location.Y=450|Corner.X=120|Corner.Y=450|LineWidth=1|Color=16711680
|RECORD=8|OwnerIndex=43|IsNotAccesible=T|IndexInSheet=180|OwnerPartId=2|Location.X=95|Location.Y=430|Radius=3|SecondaryRadius=3|LineWidth=1|Color=16711680
|RECORD=13|OwnerIndex=43|IsNotAccesible=T|IndexInSheet=181|OwnerPartId=2|Location.X=98|Location.Y=430|Corner.X=120|Corner.Y=430|LineWidth=1|Color=16711680
|RECORD=8|OwnerIndex=43|IsNotAccesible=T|IndexInSheet=182|OwnerPartId=2|Location.X=95|Location.Y=410|Radius=3|SecondaryRadius=3|LineWidth=1|Color=16711680
|RECORD=13|OwnerIndex=43|IsNotAccesible=T|IndexInSheet=183|OwnerPartId=2|Location.X=98|Location.Y=410|Corner.X=120|Corner.Y=410|LineWidth=1|Color=16711680
|RECORD=8|OwnerIndex=43|IsNotAccesible=T|IndexInSheet=184|OwnerPartId=2|Location.X=95|Location.Y=390|Radius=3|SecondaryRadius=3|LineWidth=1|Color=16711680
|RECORD=13|OwnerIndex=43|IsNotAccesible=T|IndexInSheet=185|OwnerPartId=2|Location.X=98|Location.Y=390|Corner.X=120|Corner.Y=390|LineWidth=1|Color=16711680
|RECORD=8|OwnerIndex=43|IsNotAccesible=T|IndexInSheet=186|OwnerPartId=2|Location.X=95|Location.Y=370|Radius=3|SecondaryRadius=3|LineWidth=1|Color=16711680
|RECORD=13|OwnerIndex=43|IsNotAccesible=T|IndexInSheet=187|OwnerPartId=2|Location.X=98|Location.Y=370|Corner.X=120|Corner.Y=370|LineWidth=1|Color=16711680
|RECORD=8|OwnerIndex=43|IsNotAccesible=T|IndexInSheet=188|OwnerPartId=2|Location.X=95|Location.Y=350|Radius=3|SecondaryRadius=3|LineWidth=1|Color=16711680
|RECORD=13|OwnerIndex=43|IsNotAccesible=T|IndexInSheet=189|OwnerPartId=2|Location.X=98|Location.Y=350|Corner.X=120|Corner.Y=350|LineWidth=1|Color=16711680
|RECORD=8|OwnerIndex=43|IsNotAccesible=T|IndexInSheet=190|OwnerPartId=2|Location.X=95|Location.Y=330|Radius=3|SecondaryRadius=3|LineWidth=1|Color=16711680
|RECORD=13|OwnerIndex=43|IsNotAccesible=T|IndexInSheet=191|OwnerPartId=2|Location.X=98|Location.Y=330|Corner.X=120|Corner.Y=330|LineWidth=1|Color=16711680
|RECORD=8|OwnerIndex=43|IsNotAccesible=T|IndexInSheet=192|OwnerPartId=2|Location.X=95|Location.Y=310|Radius=3|SecondaryRadius=3|LineWidth=1|Color=16711680
|RECORD=13|OwnerIndex=43|IsNotAccesible=T|IndexInSheet=193|OwnerPartId=2|Location.X=98|Location.Y=310|Corner.X=120|Corner.Y=310|LineWidth=1|Color=16711680
|RECORD=8|OwnerIndex=43|IsNotAccesible=T|IndexInSheet=194|OwnerPartId=2|Location.X=95|Location.Y=290|Radius=3|SecondaryRadius=3|LineWidth=1|Color=16711680
|RECORD=13|OwnerIndex=43|IsNotAccesible=T|IndexInSheet=195|OwnerPartId=2|Location.X=98|Location.Y=290|Corner.X=120|Corner.Y=290|LineWidth=1|Color=16711680
|RECORD=8|OwnerIndex=43|IsNotAccesible=T|IndexInSheet=196|OwnerPartId=2|Location.X=95|Location.Y=270|Radius=3|SecondaryRadius=3|LineWidth=1|Color=16711680
|RECORD=13|OwnerIndex=43|IsNotAccesible=T|IndexInSheet=197|OwnerPartId=2|Location.X=98|Location.Y=270|Corner.X=120|Corner.Y=270|LineWidth=1|Color=16711680
|RECORD=8|OwnerIndex=43|IsNotAccesible=T|IndexInSheet=198|OwnerPartId=2|Location.X=95|Location.Y=250|Radius=3|SecondaryRadius=3|LineWidth=1|Color=16711680
|RECORD=13|OwnerIndex=43|IsNotAccesible=T|IndexInSheet=199|OwnerPartId=2|Location.X=98|Location.Y=250|Corner.X=120|Corner.Y=250|LineWidth=1|Color=16711680
|RECORD=8|OwnerIndex=43|IsNotAccesible=T|IndexInSheet=200|OwnerPartId=2|Location.X=95|Location.Y=230|Radius=3|SecondaryRadius=3|LineWidth=1|Color=16711680
|RECORD=13|OwnerIndex=43|IsNotAccesible=T|IndexInSheet=201|OwnerPartId=2|Location.X=98|Location.Y=230|Corner.X=120|Corner.Y=230|LineWidth=1|Color=16711680
|RECORD=8|OwnerIndex=43|IsNotAccesible=T|IndexInSheet=202|OwnerPartId=2|Location.X=95|Location.Y=210|Radius=3|SecondaryRadius=3|LineWidth=1|Color=16711680
|RECORD=13|OwnerIndex=43|IsNotAccesible=T|IndexInSheet=203|OwnerPartId=2|Location.X=98|Location.Y=210|Corner.X=120|Corner.Y=210|LineWidth=1|Color=16711680
|RECORD=8|OwnerIndex=43|IsNotAccesible=T|IndexInSheet=204|OwnerPartId=2|Location.X=95|Location.Y=190|Radius=3|SecondaryRadius=3|LineWidth=1|Color=16711680
|RECORD=13|OwnerIndex=43|IsNotAccesible=T|IndexInSheet=205|OwnerPartId=2|Location.X=98|Location.Y=190|Corner.X=120|Corner.Y=190|LineWidth=1|Color=16711680
|RECORD=8|OwnerIndex=43|IsNotAccesible=T|IndexInSheet=206|OwnerPartId=2|Location.X=95|Location.Y=170|Radius=3|SecondaryRadius=3|LineWidth=1|Color=16711680
|RECORD=13|OwnerIndex=43|IsNotAccesible=T|IndexInSheet=207|OwnerPartId=2|Location.X=98|Location.Y=170|Corner.X=120|Corner.Y=170|LineWidth=1|Color=16711680
|RECORD=8|OwnerIndex=43|IsNotAccesible=T|IndexInSheet=208|OwnerPartId=2|Location.X=95|Location.Y=150|Radius=3|SecondaryRadius=3|LineWidth=1|Color=16711680
|RECORD=13|OwnerIndex=43|IsNotAccesible=T|IndexInSheet=209|OwnerPartId=2|Location.X=98|Location.Y=150|Corner.X=120|Corner.Y=150|LineWidth=1|Color=16711680
|RECORD=4|OwnerIndex=43|IsNotAccesible=T|IndexInSheet=210|OwnerPartId=2|Location.X=113|Location.Y=822|Justification=8|Color=8388608|FontID=1|Text=2
|RECORD=4|OwnerIndex=43|IsNotAccesible=T|IndexInSheet=211|OwnerPartId=2|Location.X=113|Location.Y=802|Justification=8|Color=8388608|FontID=1|Text=4
|RECORD=4|OwnerIndex=43|IsNotAccesible=T|IndexInSheet=212|OwnerPartId=2|Location.X=113|Location.Y=782|Justification=8|Color=8388608|FontID=1|Text=6
|RECORD=4|OwnerIndex=43|IsNotAccesible=T|IndexInSheet=213|OwnerPartId=2|Location.X=113|Location.Y=762|Justification=8|Color=8388608|FontID=1|Text=8
|RECORD=4|OwnerIndex=43|IsNotAccesible=T|IndexInSheet=214|OwnerPartId=2|Location.X=113|Location.Y=742|Justification=8|Color=8388608|FontID=1|Text=10
|RECORD=4|OwnerIndex=43|IsNotAccesible=T|IndexInSheet=215|OwnerPartId=2|Location.X=113|Location.Y=722|Justification=8|Color=8388608|FontID=1|Text=20
|RECORD=4|OwnerIndex=43|IsNotAccesible=T|IndexInSheet=216|OwnerPartId=2|Location.X=113|Location.Y=702|Justification=8|Color=8388608|FontID=1|Text=22
|RECORD=4|OwnerIndex=43|IsNotAccesible=T|IndexInSheet=217|OwnerPartId=2|Location.X=113|Location.Y=682|Justification=8|Color=8388608|FontID=1|Text=24
|RECORD=4|OwnerIndex=43|IsNotAccesible=T|IndexInSheet=218|OwnerPartId=2|Location.X=113|Location.Y=662|Justification=8|Color=8388608|FontID=1|Text=26
|RECORD=4|OwnerIndex=43|IsNotAccesible=T|IndexInSheet=219|OwnerPartId=2|Location.X=113|Location.Y=642|Justification=8|Color=8388608|FontID=1|Text=28
|RECORD=4|OwnerIndex=43|IsNotAccesible=T|IndexInSheet=220|OwnerPartId=2|Location.X=113|Location.Y=622|Justification=8|Color=8388608|FontID=1|Text=30
|RECORD=4|OwnerIndex=43|IsNotAccesible=T|IndexInSheet=221|OwnerPartId=2|Location.X=113|Location.Y=602|Justification=8|Color=8388608|FontID=1|Text=32
|RECORD=4|OwnerIndex=43|IsNotAccesible=T|IndexInSheet=222|OwnerPartId=2|Location.X=113|Location.Y=582|Justification=8|Color=8388608|FontID=1|Text=34
|RECORD=4|OwnerIndex=43|IsNotAccesible=T|IndexInSheet=223|OwnerPartId=2|Location.X=113|Location.Y=562|Justification=8|Color=8388608|FontID=1|Text=36
|RECORD=4|OwnerIndex=43|IsNotAccesible=T|IndexInSheet=224|OwnerPartId=2|Location.X=113|Location.Y=542|Justification=8|Color=8388608|FontID=1|Text=38
|RECORD=4|OwnerIndex=43|IsNotAccesible=T|IndexInSheet=225|OwnerPartId=2|Location.X=113|Location.Y=522|Justification=8|Color=8388608|FontID=1|Text=40
|RECORD=4|OwnerIndex=43|IsNotAccesible=T|IndexInSheet=226|OwnerPartId=2|Location.X=113|Location.Y=502|Justification=8|Color=8388608|FontID=1|Text=42
|RECORD=4|OwnerIndex=43|IsNotAccesible=T|IndexInSheet=227|OwnerPartId=2|Location.X=113|Location.Y=482|Justification=8|Color=8388608|FontID=1|Text=44
|RECORD=4|OwnerIndex=43|IsNotAccesible=T|IndexInSheet=228|OwnerPartId=2|Location.X=113|Location.Y=462|Justification=8|Color=8388608|FontID=1|Text=46
|RECORD=4|OwnerIndex=43|IsNotAccesible=T|IndexInSheet=229|OwnerPartId=2|Location.X=113|Location.Y=442|Justification=8|Color=8388608|FontID=1|Text=48
|RECORD=4|OwnerIndex=43|IsNotAccesible=T|IndexInSheet=230|OwnerPartId=2|Location.X=113|Location.Y=422|Justification=8|Color=8388608|FontID=1|Text=50
|RECORD=4|OwnerIndex=43|IsNotAccesible=T|IndexInSheet=231|OwnerPartId=2|Location.X=113|Location.Y=402|Justification=8|Color=8388608|FontID=1|Text=52
|RECORD=4|OwnerIndex=43|IsNotAccesible=T|IndexInSheet=232|OwnerPartId=2|Location.X=113|Location.Y=382|Justification=8|Color=8388608|FontID=1|Text=54
|RECORD=4|OwnerIndex=43|IsNotAccesible=T|IndexInSheet=233|OwnerPartId=2|Location.X=113|Location.Y=362|Justification=8|Color=8388608|FontID=1|Text=56
|RECORD=4|OwnerIndex=43|IsNotAccesible=T|IndexInSheet=234|OwnerPartId=2|Location.X=113|Location.Y=342|Justification=8|Color=8388608|FontID=1|Text=58
|RECORD=4|OwnerIndex=43|IsNotAccesible=T|IndexInSheet=235|OwnerPartId=2|Location.X=113|Location.Y=322|Justification=8|Color=8388608|FontID=1|Text=60
|RECORD=4|OwnerIndex=43|IsNotAccesible=T|IndexInSheet=236|OwnerPartId=2|Location.X=113|Location.Y=302|Justification=8|Color=8388608|FontID=1|Text=62
|RECORD=4|OwnerIndex=43|IsNotAccesible=T|IndexInSheet=237|OwnerPartId=2|Location.X=113|Location.Y=282|Justification=8|Color=8388608|FontID=1|Text=64
|RECORD=4|OwnerIndex=43|IsNotAccesible=T|IndexInSheet=238|OwnerPartId=2|Location.X=113|Location.Y=262|Justification=8|Color=8388608|FontID=1|Text=66
|RECORD=4|OwnerIndex=43|IsNotAccesible=T|IndexInSheet=239|OwnerPartId=2|Location.X=113|Location.Y=242|Justification=8|Color=8388608|FontID=1|Text=68
|RECORD=4|OwnerIndex=43|IsNotAccesible=T|IndexInSheet=240|OwnerPartId=2|Location.X=113|Location.Y=222|Justification=8|Color=8388608|FontID=1|Text=70
|RECORD=4|OwnerIndex=43|IsNotAccesible=T|IndexInSheet=241|OwnerPartId=2|Location.X=113|Location.Y=202|Justification=8|Color=8388608|FontID=1|Text=72
|RECORD=4|OwnerIndex=43|IsNotAccesible=T|IndexInSheet=242|OwnerPartId=2|Location.X=113|Location.Y=182|Justification=8|Color=8388608|FontID=1|Text=74
|RECORD=4|OwnerIndex=43|IsNotAccesible=T|IndexInSheet=243|OwnerPartId=2|Location.X=113|Location.Y=162|Justification=8|Color=8388608|FontID=1|Text=MNT 1
|RECORD=2|OwnerIndex=43|OwnerPartId=2|Electrical=4|PinConglomerate=48|PinLength=20|Location.X=120|Location.Y=810|Name=2|Designator=2|PinName_PositionConglomerate=16|Name_CustomFontID=1|PinDesignator_PositionConglomerate=16|Designator_CustomFontID=1|PinPropagationDelay=0.000000E+000
|RECORD=2|OwnerIndex=43|OwnerPartId=2|Electrical=4|PinConglomerate=48|PinLength=20|Location.X=120|Location.Y=790|Name=4|Designator=4|PinName_PositionConglomerate=16|Name_CustomFontID=1|PinDesignator_PositionConglomerate=16|Designator_CustomFontID=1|PinPropagationDelay=0.000000E+000
|RECORD=2|OwnerIndex=43|OwnerPartId=2|Electrical=4|PinConglomerate=48|PinLength=20|Location.X=120|Location.Y=770|Name=6|Designator=6|PinName_PositionConglomerate=16|Name_CustomFontID=1|PinDesignator_PositionConglomerate=16|Designator_CustomFontID=1|PinPropagationDelay=0.000000E+000
|RECORD=2|OwnerIndex=43|OwnerPartId=2|Electrical=4|PinConglomerate=48|PinLength=20|Location.X=120|Location.Y=750|Name=8|Designator=8|PinName_PositionConglomerate=16|Name_CustomFontID=1|PinDesignator_PositionConglomerate=16|Designator_CustomFontID=1|PinPropagationDelay=0.000000E+000
|RECORD=2|OwnerIndex=43|OwnerPartId=2|Electrical=4|PinConglomerate=48|PinLength=20|Location.X=120|Location.Y=730|Name=10|Designator=10|PinName_PositionConglomerate=16|Name_CustomFontID=1|PinDesignator_PositionConglomerate=16|Designator_CustomFontID=1|PinPropagationDelay=0.000000E+000
|RECORD=2|OwnerIndex=43|OwnerPartId=2|Electrical=4|PinConglomerate=48|PinLength=20|Location.X=120|Location.Y=710|Name=20|Designator=20|PinName_PositionConglomerate=16|Name_CustomFontID=1|PinDesignator_PositionConglomerate=16|Designator_CustomFontID=1|PinPropagationDelay=0.000000E+000
|RECORD=2|OwnerIndex=43|OwnerPartId=2|Electrical=4|PinConglomerate=48|PinLength=20|Location.X=120|Location.Y=690|Name=22|Designator=22|PinName_PositionConglomerate=16|Name_CustomFontID=1|PinDesignator_PositionConglomerate=16|Designator_CustomFontID=1|PinPropagationDelay=0.000000E+000
|RECORD=2|OwnerIndex=43|OwnerPartId=2|Electrical=4|PinConglomerate=48|PinLength=20|Location.X=120|Location.Y=670|Name=24|Designator=24|PinName_PositionConglomerate=16|Name_CustomFontID=1|PinDesignator_PositionConglomerate=16|Designator_CustomFontID=1|PinPropagationDelay=0.000000E+000
|RECORD=2|OwnerIndex=43|OwnerPartId=2|Electrical=4|PinConglomerate=48|PinLength=20|Location.X=120|Location.Y=650|Name=26|Designator=26|PinName_PositionConglomerate=16|Name_CustomFontID=1|PinDesignator_PositionConglomerate=16|Designator_CustomFontID=1|PinPropagationDelay=0.000000E+000
|RECORD=2|OwnerIndex=43|OwnerPartId=2|Electrical=4|PinConglomerate=48|PinLength=20|Location.X=120|Location.Y=630|Name=28|Designator=28|PinName_PositionConglomerate=16|Name_CustomFontID=1|PinDesignator_PositionConglomerate=16|Designator_CustomFontID=1|PinPropagationDelay=0.000000E+000
|RECORD=2|OwnerIndex=43|OwnerPartId=2|Electrical=4|PinConglomerate=48|PinLength=20|Location.X=120|Location.Y=610|Name=30|Designator=30|PinName_PositionConglomerate=16|Name_CustomFontID=1|PinDesignator_PositionConglomerate=16|Designator_CustomFontID=1|PinPropagationDelay=0.000000E+000
|RECORD=2|OwnerIndex=43|OwnerPartId=2|Electrical=4|PinConglomerate=48|PinLength=20|Location.X=120|Location.Y=590|Name=32|Designator=32|PinName_PositionConglomerate=16|Name_CustomFontID=1|PinDesignator_PositionConglomerate=16|Designator_CustomFontID=1|PinPropagationDelay=0.000000E+000
|RECORD=2|OwnerIndex=43|OwnerPartId=2|Electrical=4|PinConglomerate=48|PinLength=20|Location.X=120|Location.Y=570|Name=34|Designator=34|PinName_PositionConglomerate=16|Name_CustomFontID=1|PinDesignator_PositionConglomerate=16|Designator_CustomFontID=1|PinPropagationDelay=0.000000E+000
|RECORD=2|OwnerIndex=43|OwnerPartId=2|Electrical=4|PinConglomerate=48|PinLength=20|Location.X=120|Location.Y=550|Name=36|Designator=36|PinName_PositionConglomerate=16|Name_CustomFontID=1|PinDesignator_PositionConglomerate=16|Designator_CustomFontID=1|PinPropagationDelay=0.000000E+000
|RECORD=2|OwnerIndex=43|OwnerPartId=2|Electrical=4|PinConglomerate=48|PinLength=20|Location.X=120|Location.Y=530|Name=38|Designator=38|PinName_PositionConglomerate=16|Name_CustomFontID=1|PinDesignator_PositionConglomerate=16|Designator_CustomFontID=1|PinPropagationDelay=0.000000E+000
|RECORD=2|OwnerIndex=43|OwnerPartId=2|Electrical=4|PinConglomerate=48|PinLength=20|Location.X=120|Location.Y=510|Name=40|Designator=40|PinName_PositionConglomerate=16|Name_CustomFontID=1|PinDesignator_PositionConglomerate=16|Designator_CustomFontID=1|PinPropagationDelay=0.000000E+000
|RECORD=2|OwnerIndex=43|OwnerPartId=2|Electrical=4|PinConglomerate=48|PinLength=20|Location.X=120|Location.Y=490|Name=42|Designator=42|PinName_PositionConglomerate=16|Name_CustomFontID=1|PinDesignator_PositionConglomerate=16|Designator_CustomFontID=1|PinPropagationDelay=0.000000E+000
|RECORD=2|OwnerIndex=43|OwnerPartId=2|Electrical=4|PinConglomerate=48|PinLength=20|Location.X=120|Location.Y=470|Name=44|Designator=44|PinName_PositionConglomerate=16|Name_CustomFontID=1|PinDesignator_PositionConglomerate=16|Designator_CustomFontID=1|PinPropagationDelay=0.000000E+000
|RECORD=2|OwnerIndex=43|OwnerPartId=2|Electrical=4|PinConglomerate=48|PinLength=20|Location.X=120|Location.Y=450|Name=46|Designator=46|PinName_PositionConglomerate=16|Name_CustomFontID=1|PinDesignator_PositionConglomerate=16|Designator_CustomFontID=1|PinPropagationDelay=0.000000E+000
|RECORD=2|OwnerIndex=43|OwnerPartId=2|Electrical=4|PinConglomerate=48|PinLength=20|Location.X=120|Location.Y=430|Name=48|Designator=48|PinName_PositionConglomerate=16|Name_CustomFontID=1|PinDesignator_PositionConglomerate=16|Designator_CustomFontID=1|PinPropagationDelay=0.000000E+000
|RECORD=2|OwnerIndex=43|OwnerPartId=2|Electrical=4|PinConglomerate=48|PinLength=20|Location.X=120|Location.Y=410|Name=50|Designator=50|PinName_PositionConglomerate=16|Name_CustomFontID=1|PinDesignator_PositionConglomerate=16|Designator_CustomFontID=1|PinPropagationDelay=0.000000E+000
|RECORD=2|OwnerIndex=43|OwnerPartId=2|Electrical=4|PinConglomerate=48|PinLength=20|Location.X=120|Location.Y=390|Name=52|Designator=52|PinName_PositionConglomerate=16|Name_CustomFontID=1|PinDesignator_PositionConglomerate=16|Designator_CustomFontID=1|PinPropagationDelay=0.000000E+000
|RECORD=2|OwnerIndex=43|OwnerPartId=2|Electrical=4|PinConglomerate=48|PinLength=20|Location.X=120|Location.Y=370|Name=54|Designator=54|PinName_PositionConglomerate=16|Name_CustomFontID=1|PinDesignator_PositionConglomerate=16|Designator_CustomFontID=1|PinPropagationDelay=0.000000E+000
|RECORD=2|OwnerIndex=43|OwnerPartId=2|Electrical=4|PinConglomerate=48|PinLength=20|Location.X=120|Location.Y=350|Name=56|Designator=56|PinName_PositionConglomerate=16|Name_CustomFontID=1|PinDesignator_PositionConglomerate=16|Designator_CustomFontID=1|PinPropagationDelay=0.000000E+000
|RECORD=2|OwnerIndex=43|OwnerPartId=2|Electrical=4|PinConglomerate=48|PinLength=20|Location.X=120|Location.Y=330|Name=58|Designator=58|PinName_PositionConglomerate=16|Name_CustomFontID=1|PinDesignator_PositionConglomerate=16|Designator_CustomFontID=1|PinPropagationDelay=0.000000E+000
|RECORD=2|OwnerIndex=43|OwnerPartId=2|Electrical=4|PinConglomerate=48|PinLength=20|Location.X=120|Location.Y=310|Name=60|Designator=60|PinName_PositionConglomerate=16|Name_CustomFontID=1|PinDesignator_PositionConglomerate=16|Designator_CustomFontID=1|PinPropagationDelay=0.000000E+000
|RECORD=2|OwnerIndex=43|OwnerPartId=2|Electrical=4|PinConglomerate=48|PinLength=20|Location.X=120|Location.Y=290|Name=62|Designator=62|PinName_PositionConglomerate=16|Name_CustomFontID=1|PinDesignator_PositionConglomerate=16|Designator_CustomFontID=1|PinPropagationDelay=0.000000E+000
|RECORD=2|OwnerIndex=43|OwnerPartId=2|Electrical=4|PinConglomerate=48|PinLength=20|Location.X=120|Location.Y=270|Name=64|Designator=64|PinName_PositionConglomerate=16|Name_CustomFontID=1|PinDesignator_PositionConglomerate=16|Designator_CustomFontID=1|PinPropagationDelay=0.000000E+000
|RECORD=2|OwnerIndex=43|OwnerPartId=2|Electrical=4|PinConglomerate=48|PinLength=20|Location.X=120|Location.Y=250|Name=66|Designator=66|PinName_PositionConglomerate=16|Name_CustomFontID=1|PinDesignator_PositionConglomerate=16|Designator_CustomFontID=1|PinPropagationDelay=0.000000E+000
|RECORD=2|OwnerIndex=43|OwnerPartId=2|Electrical=4|PinConglomerate=48|PinLength=20|Location.X=120|Location.Y=230|Name=68|Designator=68|PinName_PositionConglomerate=16|Name_CustomFontID=1|PinDesignator_PositionConglomerate=16|Designator_CustomFontID=1|PinPropagationDelay=0.000000E+000
|RECORD=2|OwnerIndex=43|OwnerPartId=2|Electrical=4|PinConglomerate=48|PinLength=20|Location.X=120|Location.Y=210|Name=70|Designator=70|PinName_PositionConglomerate=16|Name_CustomFontID=1|PinDesignator_PositionConglomerate=16|Designator_CustomFontID=1|PinPropagationDelay=0.000000E+000
|RECORD=2|OwnerIndex=43|OwnerPartId=2|Electrical=4|PinConglomerate=48|PinLength=20|Location.X=120|Location.Y=190|Name=72|Designator=72|PinName_PositionConglomerate=16|Name_CustomFontID=1|PinDesignator_PositionConglomerate=16|Designator_CustomFontID=1|PinPropagationDelay=0.000000E+000
|RECORD=2|OwnerIndex=43|OwnerPartId=2|Electrical=4|PinConglomerate=48|PinLength=20|Location.X=120|Location.Y=170|Name=74|Designator=74|PinName_PositionConglomerate=16|Name_CustomFontID=1|PinDesignator_PositionConglomerate=16|Designator_CustomFontID=1|PinPropagationDelay=0.000000E+000
|RECORD=2|OwnerIndex=43|OwnerPartId=2|Electrical=4|PinConglomerate=48|PinLength=20|Location.X=120|Location.Y=150|Name=MNT 1|Designator=76|PinName_PositionConglomerate=16|Name_CustomFontID=1|PinDesignator_PositionConglomerate=16|Designator_CustomFontID=1|PinPropagationDelay=0.000000E+000
|RECORD=41|OwnerIndex=43|IndexInSheet=278|OwnerPartId=-1|Location.X=70|Location.Y=830|Color=8388608|FontID=1|IsHidden=T|Text=500mA|Name=Contact Current Rating
|RECORD=41|OwnerIndex=43|IndexInSheet=279|OwnerPartId=-1|Location.X=70|Location.Y=830|Color=8388608|FontID=1|IsHidden=T|Text=67|Name=Number of Contacts
|RECORD=41|OwnerIndex=43|IndexInSheet=280|OwnerPartId=-1|Location.X=70|Location.Y=830|Color=8388608|FontID=1|IsHidden=T|Text=Right Angle|Name=Orientation
|RECORD=41|OwnerIndex=43|IndexInSheet=281|OwnerPartId=-1|Location.X=70|Location.Y=830|Color=8388608|FontID=1|IsHidden=T|Text=0.862inch|Name=Length
|RECORD=41|OwnerIndex=43|IndexInSheet=282|OwnerPartId=-1|Location.X=70|Location.Y=830|Color=8388608|FontID=1|IsHidden=T|Text=No|Name=Radiation Hardening
|RECORD=41|OwnerIndex=43|IndexInSheet=283|OwnerPartId=-1|Location.X=70|Location.Y=830|Color=8388608|FontID=1|IsHidden=T|Text=Right Angle|Name=PCB Mounting Orientation
|RECORD=41|OwnerIndex=43|IndexInSheet=284|OwnerPartId=-1|Location.X=70|Location.Y=830|Color=8388608|FontID=1|IsHidden=T|Text=Surface Mount|Name=Mount
|RECORD=41|OwnerIndex=43|IndexInSheet=285|OwnerPartId=-1|Location.X=70|Location.Y=830|Color=8388608|FontID=1|IsHidden=T|Text=Gold|Name=Contact Plating
|RECORD=41|OwnerIndex=43|IndexInSheet=286|OwnerPartId=-1|Location.X=70|Location.Y=830|Color=8388608|FontID=1|IsHidden=T|Text=Copper Alloy|Name=Contact Material
|RECORD=41|OwnerIndex=43|IndexInSheet=287|OwnerPartId=-1|Location.X=70|Location.Y=830|Color=8388608|FontID=1|IsHidden=T|Text=8.7mm|Name=Width
|RECORD=41|OwnerIndex=43|IndexInSheet=288|OwnerPartId=-1|Location.X=70|Location.Y=830|Color=8388608|FontID=1|IsHidden=T|Text=2|Name=Number of Rows
|RECORD=41|OwnerIndex=43|IndexInSheet=289|OwnerPartId=-1|Location.X=70|Location.Y=830|Color=8388608|FontID=1|IsHidden=T|Text=Black|Name=Color
|RECORD=41|OwnerIndex=43|IndexInSheet=290|OwnerPartId=-1|Location.X=70|Location.Y=830|Color=8388608|FontID=1|IsHidden=T|Text=0.5mm|Name=Pitch
|RECORD=41|OwnerIndex=43|IndexInSheet=291|OwnerPartId=-1|Location.X=70|Location.Y=830|Color=8388608|FontID=1|IsHidden=T|Text=Compliant|Name=ELV
|RECORD=41|OwnerIndex=43|IndexInSheet=292|OwnerPartId=-1|Location.X=70|Location.Y=830|Color=8388608|FontID=1|IsHidden=T|Text=Black|Name=Housing Color
|RECORD=41|OwnerIndex=43|IndexInSheet=293|OwnerPartId=-1|Location.X=70|Location.Y=830|Color=8388608|FontID=1|IsHidden=T|Text=50V|Name=Voltage Rating
|RECORD=41|OwnerIndex=43|IndexInSheet=294|OwnerPartId=-1|Location.X=70|Location.Y=830|Color=8388608|FontID=1|IsHidden=T|Text=67|Name=Number of Positions
|RECORD=41|OwnerIndex=43|IndexInSheet=295|OwnerPartId=-1|Location.X=70|Location.Y=830|Color=8388608|FontID=1|IsHidden=T|Text=Thermoplastic|Name=Housing Material
|RECORD=41|OwnerIndex=43|IndexInSheet=296|OwnerPartId=-1|Location.X=70|Location.Y=830|Color=8388608|FontID=1|IsHidden=T|Text=Female|Name=Gender
|RECORD=41|OwnerIndex=43|IndexInSheet=297|OwnerPartId=-1|Location.X=70|Location.Y=830|Color=8388608|FontID=1|IsHidden=T|Text=-40°C|Name=Min Operating Temperature
|RECORD=41|OwnerIndex=43|IndexInSheet=298|OwnerPartId=-1|Location.X=70|Location.Y=830|Color=8388608|FontID=1|IsHidden=T|Text=80°C|Name=Max Operating Temperature
|RECORD=41|OwnerIndex=43|IndexInSheet=299|OwnerPartId=-1|Location.X=70|Location.Y=830|Color=8388608|FontID=1|IsHidden=T|Text=500MR|Name=Insulation Resistance
|RECORD=41|OwnerIndex=43|IndexInSheet=300|OwnerPartId=-1|Location.X=70|Location.Y=830|Color=8388608|FontID=1|IsHidden=T|Text=7.55mm|Name=Row Spacing
|RECORD=41|OwnerIndex=43|IndexInSheet=301|OwnerPartId=-1|Location.X=70|Location.Y=830|Color=8388608|FontID=1|IsHidden=T|Text=Yes|Name=RoHS Compliant
|RECORD=41|OwnerIndex=43|IndexInSheet=302|OwnerPartId=-1|Location.X=70|Location.Y=830|Color=8388608|FontID=1|IsHidden=T|Text=1200|Name=Package Quantity
|RECORD=41|OwnerIndex=43|IndexInSheet=303|OwnerPartId=-1|Location.X=70|Location.Y=830|Color=8388608|FontID=1|IsHidden=T|Text=Tape and Reel|Name=Packaging
|RECORD=41|OwnerIndex=43|IndexInSheet=304|OwnerPartId=-1|Location.X=70|Location.Y=830|Color=8388608|FontID=1|IsHidden=T|Text=3.2mm|Name=Height
|RECORD=41|OwnerIndex=43|IndexInSheet=305|OwnerPartId=-1|Location.X=70|Location.Y=830|Color=8388608|FontID=1|IsHidden=T|Text=Solder|Name=Termination
|RECORD=41|OwnerIndex=43|IndexInSheet=306|OwnerPartId=-1|Location.X=70|Location.Y=830|Color=8388608|FontID=1|IsHidden=T|Text=Thermoplastic|Name=Insulation Material
|RECORD=41|OwnerIndex=43|IndexInSheet=307|OwnerPartId=-1|Location.X=70|Location.Y=830|Color=8388608|FontID=1|IsHidden=T|Text=50V|Name=Max Voltage Rating (AC)
|RECORD=41|OwnerIndex=43|IndexInSheet=308|OwnerPartId=-1|Location.X=70|Location.Y=830|Color=8388608|FontID=1|IsHidden=T|Text=500mA|Name=Current Rating
|RECORD=34|OwnerIndex=43|IndexInSheet=-1|OwnerPartId=-1|Location.X=70|Location.Y=830|Color=8388608|FontID=1|Text=J44|Name=Designator|ReadOnlyState=1
|RECORD=41|OwnerIndex=43|IndexInSheet=-1|OwnerPartId=1|Location.X=70|Location.Y=100|Color=8388608|FontID=1|Text=2199119-3|Name=Comment
|RECORD=44|OwnerIndex=43
|RECORD=45|OwnerIndex=424|IndexInSheet=-1|UseComponentLibrary=T|ModelName=FP-2199119-3-MFG|ModelType=PCBLIB|DatafileCount=1|ModelDatafileEntity0=FP-2199119-3-MFG|ModelDatafileKind0=PCBLib|IsCurrent=T|DatalinksLocked=T|DatabaseDatalinksLocked=T
|RECORD=46|OwnerIndex=425
|RECORD=48|OwnerIndex=425
|RECORD=1|LibReference=a14843ccfa78e5d0b739856168502fb|ComponentDescription=CONN M.2 FEMALE 67POS 0.020 GOLD|PartCount=3|DisplayModeCount=1|IndexInSheet=43|OwnerPartId=-1|Location.X=430|Location.Y=800|CurrentPartId=2|LibraryPath=*|SourceLibraryName=Altium Content Vault|TargetFileName=*|AreaColor=11599871|Color=128|PartIDLocked=T|DesignItemId=CMP-03365-000004-1|AllPinCount=69
|RECORD=14|OwnerIndex=428|IsNotAccesible=T|OwnerPartId=1|Location.X=360|Location.Y=100|Corner.X=410|Corner.Y=820|LineWidth=1|Color=128|AreaColor=11599871|IsSolid=T
|RECORD=8|OwnerIndex=428|IsNotAccesible=T|IndexInSheet=1|OwnerPartId=1|Location.X=385|Location.Y=800|Radius=3|SecondaryRadius=3|LineWidth=1|Color=16711680
|RECORD=13|OwnerIndex=428|IsNotAccesible=T|IndexInSheet=2|OwnerPartId=1|Location.X=388|Location.Y=800|Corner.X=410|Corner.Y=800|LineWidth=1|Color=16711680
|RECORD=8|OwnerIndex=428|IsNotAccesible=T|IndexInSheet=3|OwnerPartId=1|Location.X=385|Location.Y=780|Radius=3|SecondaryRadius=3|LineWidth=1|Color=16711680
|RECORD=13|OwnerIndex=428|IsNotAccesible=T|IndexInSheet=4|OwnerPartId=1|Location.X=388|Location.Y=780|Corner.X=410|Corner.Y=780|LineWidth=1|Color=16711680
|RECORD=8|OwnerIndex=428|IsNotAccesible=T|IndexInSheet=5|OwnerPartId=1|Location.X=385|Location.Y=760|Radius=3|SecondaryRadius=3|LineWidth=1|Color=16711680
|RECORD=13|OwnerIndex=428|IsNotAccesible=T|IndexInSheet=6|OwnerPartId=1|Location.X=388|Location.Y=760|Corner.X=410|Corner.Y=760|LineWidth=1|Color=16711680
|RECORD=8|OwnerIndex=428|IsNotAccesible=T|IndexInSheet=7|OwnerPartId=1|Location.X=385|Location.Y=740|Radius=3|SecondaryRadius=3|LineWidth=1|Color=16711680
|RECORD=13|OwnerIndex=428|IsNotAccesible=T|IndexInSheet=8|OwnerPartId=1|Location.X=388|Location.Y=740|Corner.X=410|Corner.Y=740|LineWidth=1|Color=16711680
|RECORD=8|OwnerIndex=428|IsNotAccesible=T|IndexInSheet=9|OwnerPartId=1|Location.X=385|Location.Y=720|Radius=3|SecondaryRadius=3|LineWidth=1|Color=16711680
|RECORD=13|OwnerIndex=428|IsNotAccesible=T|IndexInSheet=10|OwnerPartId=1|Location.X=388|Location.Y=720|Corner.X=410|Corner.Y=720|LineWidth=1|Color=16711680
|RECORD=8|OwnerIndex=428|IsNotAccesible=T|IndexInSheet=11|OwnerPartId=1|Location.X=385|Location.Y=700|Radius=3|SecondaryRadius=3|LineWidth=1|Color=16711680
|RECORD=13|OwnerIndex=428|IsNotAccesible=T|IndexInSheet=12|OwnerPartId=1|Location.X=388|Location.Y=700|Corner.X=410|Corner.Y=700|LineWidth=1|Color=16711680
|RECORD=8|OwnerIndex=428|IsNotAccesible=T|IndexInSheet=13|OwnerPartId=1|Location.X=385|Location.Y=680|Radius=3|SecondaryRadius=3|LineWidth=1|Color=16711680
|RECORD=13|OwnerIndex=428|IsNotAccesible=T|IndexInSheet=14|OwnerPartId=1|Location.X=388|Location.Y=680|Corner.X=410|Corner.Y=680|LineWidth=1|Color=16711680
|RECORD=8|OwnerIndex=428|IsNotAccesible=T|IndexInSheet=15|OwnerPartId=1|Location.X=385|Location.Y=660|Radius=3|SecondaryRadius=3|LineWidth=1|Color=16711680
|RECORD=13|OwnerIndex=428|IsNotAccesible=T|IndexInSheet=16|OwnerPartId=1|Location.X=388|Location.Y=660|Corner.X=410|Corner.Y=660|LineWidth=1|Color=16711680
|RECORD=8|OwnerIndex=428|IsNotAccesible=T|IndexInSheet=17|OwnerPartId=1|Location.X=385|Location.Y=640|Radius=3|SecondaryRadius=3|LineWidth=1|Color=16711680
|RECORD=13|OwnerIndex=428|IsNotAccesible=T|IndexInSheet=18|OwnerPartId=1|Location.X=388|Location.Y=640|Corner.X=410|Corner.Y=640|LineWidth=1|Color=16711680
|RECORD=8|OwnerIndex=428|IsNotAccesible=T|IndexInSheet=19|OwnerPartId=1|Location.X=385|Location.Y=620|Radius=3|SecondaryRadius=3|LineWidth=1|Color=16711680
|RECORD=13|OwnerIndex=428|IsNotAccesible=T|IndexInSheet=20|OwnerPartId=1|Location.X=388|Location.Y=620|Corner.X=410|Corner.Y=620|LineWidth=1|Color=16711680
|RECORD=8|OwnerIndex=428|IsNotAccesible=T|IndexInSheet=21|OwnerPartId=1|Location.X=385|Location.Y=600|Radius=3|SecondaryRadius=3|LineWidth=1|Color=16711680
|RECORD=13|OwnerIndex=428|IsNotAccesible=T|IndexInSheet=22|OwnerPartId=1|Location.X=388|Location.Y=600|Corner.X=410|Corner.Y=600|LineWidth=1|Color=16711680
|RECORD=8|OwnerIndex=428|IsNotAccesible=T|IndexInSheet=23|OwnerPartId=1|Location.X=385|Location.Y=580|Radius=3|SecondaryRadius=3|LineWidth=1|Color=16711680
|RECORD=13|OwnerIndex=428|IsNotAccesible=T|IndexInSheet=24|OwnerPartId=1|Location.X=388|Location.Y=580|Corner.X=410|Corner.Y=580|LineWidth=1|Color=16711680
|RECORD=8|OwnerIndex=428|IsNotAccesible=T|IndexInSheet=25|OwnerPartId=1|Location.X=385|Location.Y=560|Radius=3|SecondaryRadius=3|LineWidth=1|Color=16711680
|RECORD=13|OwnerIndex=428|IsNotAccesible=T|IndexInSheet=26|OwnerPartId=1|Location.X=388|Location.Y=560|Corner.X=410|Corner.Y=560|LineWidth=1|Color=16711680
|RECORD=8|OwnerIndex=428|IsNotAccesible=T|IndexInSheet=27|OwnerPartId=1|Location.X=385|Location.Y=540|Radius=3|SecondaryRadius=3|LineWidth=1|Color=16711680
|RECORD=13|OwnerIndex=428|IsNotAccesible=T|IndexInSheet=28|OwnerPartId=1|Location.X=388|Location.Y=540|Corner.X=410|Corner.Y=540|LineWidth=1|Color=16711680
|RECORD=8|OwnerIndex=428|IsNotAccesible=T|IndexInSheet=29|OwnerPartId=1|Location.X=385|Location.Y=520|Radius=3|SecondaryRadius=3|LineWidth=1|Color=16711680
|RECORD=13|OwnerIndex=428|IsNotAccesible=T|IndexInSheet=30|OwnerPartId=1|Location.X=388|Location.Y=520|Corner.X=410|Corner.Y=520|LineWidth=1|Color=16711680
|RECORD=8|OwnerIndex=428|IsNotAccesible=T|IndexInSheet=31|OwnerPartId=1|Location.X=385|Location.Y=500|Radius=3|SecondaryRadius=3|LineWidth=1|Color=16711680
|RECORD=13|OwnerIndex=428|IsNotAccesible=T|IndexInSheet=32|OwnerPartId=1|Location.X=388|Location.Y=500|Corner.X=410|Corner.Y=500|LineWidth=1|Color=16711680
|RECORD=8|OwnerIndex=428|IsNotAccesible=T|IndexInSheet=33|OwnerPartId=1|Location.X=385|Location.Y=480|Radius=3|SecondaryRadius=3|LineWidth=1|Color=16711680
|RECORD=13|OwnerIndex=428|IsNotAccesible=T|IndexInSheet=34|OwnerPartId=1|Location.X=388|Location.Y=480|Corner.X=410|Corner.Y=480|LineWidth=1|Color=16711680
|RECORD=8|OwnerIndex=428|IsNotAccesible=T|IndexInSheet=35|OwnerPartId=1|Location.X=385|Location.Y=460|Radius=3|SecondaryRadius=3|LineWidth=1|Color=16711680
|RECORD=13|OwnerIndex=428|IsNotAccesible=T|IndexInSheet=36|OwnerPartId=1|Location.X=388|Location.Y=460|Corner.X=410|Corner.Y=460|LineWidth=1|Color=16711680
|RECORD=8|OwnerIndex=428|IsNotAccesible=T|IndexInSheet=37|OwnerPartId=1|Location.X=385|Location.Y=440|Radius=3|SecondaryRadius=3|LineWidth=1|Color=16711680
|RECORD=13|OwnerIndex=428|IsNotAccesible=T|IndexInSheet=38|OwnerPartId=1|Location.X=388|Location.Y=440|Corner.X=410|Corner.Y=440|LineWidth=1|Color=16711680
|RECORD=8|OwnerIndex=428|IsNotAccesible=T|IndexInSheet=39|OwnerPartId=1|Location.X=385|Location.Y=420|Radius=3|SecondaryRadius=3|LineWidth=1|Color=16711680
|RECORD=13|OwnerIndex=428|IsNotAccesible=T|IndexInSheet=40|OwnerPartId=1|Location.X=388|Location.Y=420|Corner.X=410|Corner.Y=420|LineWidth=1|Color=16711680
|RECORD=8|OwnerIndex=428|IsNotAccesible=T|IndexInSheet=41|OwnerPartId=1|Location.X=385|Location.Y=400|Radius=3|SecondaryRadius=3|LineWidth=1|Color=16711680
|RECORD=13|OwnerIndex=428|IsNotAccesible=T|IndexInSheet=42|OwnerPartId=1|Location.X=388|Location.Y=400|Corner.X=410|Corner.Y=400|LineWidth=1|Color=16711680
|RECORD=8|OwnerIndex=428|IsNotAccesible=T|IndexInSheet=43|OwnerPartId=1|Location.X=385|Location.Y=380|Radius=3|SecondaryRadius=3|LineWidth=1|Color=16711680
|RECORD=13|OwnerIndex=428|IsNotAccesible=T|IndexInSheet=44|OwnerPartId=1|Location.X=388|Location.Y=380|Corner.X=410|Corner.Y=380|LineWidth=1|Color=16711680
|RECORD=8|OwnerIndex=428|IsNotAccesible=T|IndexInSheet=45|OwnerPartId=1|Location.X=385|Location.Y=360|Radius=3|SecondaryRadius=3|LineWidth=1|Color=16711680
|RECORD=13|OwnerIndex=428|IsNotAccesible=T|IndexInSheet=46|OwnerPartId=1|Location.X=388|Location.Y=360|Corner.X=410|Corner.Y=360|LineWidth=1|Color=16711680
|RECORD=8|OwnerIndex=428|IsNotAccesible=T|IndexInSheet=47|OwnerPartId=1|Location.X=385|Location.Y=340|Radius=3|SecondaryRadius=3|LineWidth=1|Color=16711680
|RECORD=13|OwnerIndex=428|IsNotAccesible=T|IndexInSheet=48|OwnerPartId=1|Location.X=388|Location.Y=340|Corner.X=410|Corner.Y=340|LineWidth=1|Color=16711680
|RECORD=8|OwnerIndex=428|IsNotAccesible=T|IndexInSheet=49|OwnerPartId=1|Location.X=385|Location.Y=320|Radius=3|SecondaryRadius=3|LineWidth=1|Color=16711680
|RECORD=13|OwnerIndex=428|IsNotAccesible=T|IndexInSheet=50|OwnerPartId=1|Location.X=388|Location.Y=320|Corner.X=410|Corner.Y=320|LineWidth=1|Color=16711680
|RECORD=8|OwnerIndex=428|IsNotAccesible=T|IndexInSheet=51|OwnerPartId=1|Location.X=385|Location.Y=300|Radius=3|SecondaryRadius=3|LineWidth=1|Color=16711680
|RECORD=13|OwnerIndex=428|IsNotAccesible=T|IndexInSheet=52|OwnerPartId=1|Location.X=388|Location.Y=300|Corner.X=410|Corner.Y=300|LineWidth=1|Color=16711680
|RECORD=8|OwnerIndex=428|IsNotAccesible=T|IndexInSheet=53|OwnerPartId=1|Location.X=385|Location.Y=280|Radius=3|SecondaryRadius=3|LineWidth=1|Color=16711680
|RECORD=13|OwnerIndex=428|IsNotAccesible=T|IndexInSheet=54|OwnerPartId=1|Location.X=388|Location.Y=280|Corner.X=410|Corner.Y=280|LineWidth=1|Color=16711680
|RECORD=8|OwnerIndex=428|IsNotAccesible=T|IndexInSheet=55|OwnerPartId=1|Location.X=385|Location.Y=260|Radius=3|SecondaryRadius=3|LineWidth=1|Color=16711680
|RECORD=13|OwnerIndex=428|IsNotAccesible=T|IndexInSheet=56|OwnerPartId=1|Location.X=388|Location.Y=260|Corner.X=410|Corner.Y=260|LineWidth=1|Color=16711680
|RECORD=8|OwnerIndex=428|IsNotAccesible=T|IndexInSheet=57|OwnerPartId=1|Location.X=385|Location.Y=240|Radius=3|SecondaryRadius=3|LineWidth=1|Color=16711680
|RECORD=13|OwnerIndex=428|IsNotAccesible=T|IndexInSheet=58|OwnerPartId=1|Location.X=388|Location.Y=240|Corner.X=410|Corner.Y=240|LineWidth=1|Color=16711680
|RECORD=8|OwnerIndex=428|IsNotAccesible=T|IndexInSheet=59|OwnerPartId=1|Location.X=385|Location.Y=220|Radius=3|SecondaryRadius=3|LineWidth=1|Color=16711680
|RECORD=13|OwnerIndex=428|IsNotAccesible=T|IndexInSheet=60|OwnerPartId=1|Location.X=388|Location.Y=220|Corner.X=410|Corner.Y=220|LineWidth=1|Color=16711680
|RECORD=8|OwnerIndex=428|IsNotAccesible=T|IndexInSheet=61|OwnerPartId=1|Location.X=385|Location.Y=200|Radius=3|SecondaryRadius=3|LineWidth=1|Color=16711680
|RECORD=13|OwnerIndex=428|IsNotAccesible=T|IndexInSheet=62|OwnerPartId=1|Location.X=388|Location.Y=200|Corner.X=410|Corner.Y=200|LineWidth=1|Color=16711680
|RECORD=8|OwnerIndex=428|IsNotAccesible=T|IndexInSheet=63|OwnerPartId=1|Location.X=385|Location.Y=180|Radius=3|SecondaryRadius=3|LineWidth=1|Color=16711680
|RECORD=13|OwnerIndex=428|IsNotAccesible=T|IndexInSheet=64|OwnerPartId=1|Location.X=388|Location.Y=180|Corner.X=410|Corner.Y=180|LineWidth=1|Color=16711680
|RECORD=8|OwnerIndex=428|IsNotAccesible=T|IndexInSheet=65|OwnerPartId=1|Location.X=385|Location.Y=160|Radius=3|SecondaryRadius=3|LineWidth=1|Color=16711680
|RECORD=13|OwnerIndex=428|IsNotAccesible=T|IndexInSheet=66|OwnerPartId=1|Location.X=388|Location.Y=160|Corner.X=410|Corner.Y=160|LineWidth=1|Color=16711680
|RECORD=8|OwnerIndex=428|IsNotAccesible=T|IndexInSheet=67|OwnerPartId=1|Location.X=385|Location.Y=140|Radius=3|SecondaryRadius=3|LineWidth=1|Color=16711680
|RECORD=13|OwnerIndex=428|IsNotAccesible=T|IndexInSheet=68|OwnerPartId=1|Location.X=388|Location.Y=140|Corner.X=410|Corner.Y=140|LineWidth=1|Color=16711680
|RECORD=8|OwnerIndex=428|IsNotAccesible=T|IndexInSheet=69|OwnerPartId=1|Location.X=385|Location.Y=120|Radius=3|SecondaryRadius=3|LineWidth=1|Color=16711680
|RECORD=13|OwnerIndex=428|IsNotAccesible=T|IndexInSheet=70|OwnerPartId=1|Location.X=388|Location.Y=120|Corner.X=410|Corner.Y=120|LineWidth=1|Color=16711680
|RECORD=4|OwnerIndex=428|IsNotAccesible=T|IndexInSheet=71|OwnerPartId=1|Location.X=403|Location.Y=812|Justification=8|Color=8388608|FontID=1|Text=1
|RECORD=4|OwnerIndex=428|IsNotAccesible=T|IndexInSheet=72|OwnerPartId=1|Location.X=403|Location.Y=792|Justification=8|Color=8388608|FontID=1|Text=3
|RECORD=4|OwnerIndex=428|IsNotAccesible=T|IndexInSheet=73|OwnerPartId=1|Location.X=403|Location.Y=772|Justification=8|Color=8388608|FontID=1|Text=5
|RECORD=4|OwnerIndex=428|IsNotAccesible=T|IndexInSheet=74|OwnerPartId=1|Location.X=403|Location.Y=752|Justification=8|Color=8388608|FontID=1|Text=7
|RECORD=4|OwnerIndex=428|IsNotAccesible=T|IndexInSheet=75|OwnerPartId=1|Location.X=403|Location.Y=732|Justification=8|Color=8388608|FontID=1|Text=9
|RECORD=4|OwnerIndex=428|IsNotAccesible=T|IndexInSheet=76|OwnerPartId=1|Location.X=403|Location.Y=712|Justification=8|Color=8388608|FontID=1|Text=11
|RECORD=4|OwnerIndex=428|IsNotAccesible=T|IndexInSheet=77|OwnerPartId=1|Location.X=403|Location.Y=692|Justification=8|Color=8388608|FontID=1|Text=21
|RECORD=4|OwnerIndex=428|IsNotAccesible=T|IndexInSheet=78|OwnerPartId=1|Location.X=403|Location.Y=672|Justification=8|Color=8388608|FontID=1|Text=23
|RECORD=4|OwnerIndex=428|IsNotAccesible=T|IndexInSheet=79|OwnerPartId=1|Location.X=403|Location.Y=652|Justification=8|Color=8388608|FontID=1|Text=25
|RECORD=4|OwnerIndex=428|IsNotAccesible=T|IndexInSheet=80|OwnerPartId=1|Location.X=403|Location.Y=632|Justification=8|Color=8388608|FontID=1|Text=27
|RECORD=4|OwnerIndex=428|IsNotAccesible=T|IndexInSheet=81|OwnerPartId=1|Location.X=403|Location.Y=612|Justification=8|Color=8388608|FontID=1|Text=29
|RECORD=4|OwnerIndex=428|IsNotAccesible=T|IndexInSheet=82|OwnerPartId=1|Location.X=403|Location.Y=592|Justification=8|Color=8388608|FontID=1|Text=31
|RECORD=4|OwnerIndex=428|IsNotAccesible=T|IndexInSheet=83|OwnerPartId=1|Location.X=403|Location.Y=572|Justification=8|Color=8388608|FontID=1|Text=33
|RECORD=4|OwnerIndex=428|IsNotAccesible=T|IndexInSheet=84|OwnerPartId=1|Location.X=403|Location.Y=552|Justification=8|Color=8388608|FontID=1|Text=35
|RECORD=4|OwnerIndex=428|IsNotAccesible=T|IndexInSheet=85|OwnerPartId=1|Location.X=403|Location.Y=532|Justification=8|Color=8388608|FontID=1|Text=37
|RECORD=4|OwnerIndex=428|IsNotAccesible=T|IndexInSheet=86|OwnerPartId=1|Location.X=403|Location.Y=512|Justification=8|Color=8388608|FontID=1|Text=39
|RECORD=4|OwnerIndex=428|IsNotAccesible=T|IndexInSheet=87|OwnerPartId=1|Location.X=403|Location.Y=492|Justification=8|Color=8388608|FontID=1|Text=41
|RECORD=4|OwnerIndex=428|IsNotAccesible=T|IndexInSheet=88|OwnerPartId=1|Location.X=403|Location.Y=472|Justification=8|Color=8388608|FontID=1|Text=43
|RECORD=4|OwnerIndex=428|IsNotAccesible=T|IndexInSheet=89|OwnerPartId=1|Location.X=403|Location.Y=452|Justification=8|Color=8388608|FontID=1|Text=45
|RECORD=4|OwnerIndex=428|IsNotAccesible=T|IndexInSheet=90|OwnerPartId=1|Location.X=403|Location.Y=432|Justification=8|Color=8388608|FontID=1|Text=47
|RECORD=4|OwnerIndex=428|IsNotAccesible=T|IndexInSheet=91|OwnerPartId=1|Location.X=403|Location.Y=412|Justification=8|Color=8388608|FontID=1|Text=49
|RECORD=4|OwnerIndex=428|IsNotAccesible=T|IndexInSheet=92|OwnerPartId=1|Location.X=403|Location.Y=392|Justification=8|Color=8388608|FontID=1|Text=51
|RECORD=4|OwnerIndex=428|IsNotAccesible=T|IndexInSheet=93|OwnerPartId=1|Location.X=403|Location.Y=372|Justification=8|Color=8388608|FontID=1|Text=53
|RECORD=4|OwnerIndex=428|IsNotAccesible=T|IndexInSheet=94|OwnerPartId=1|Location.X=403|Location.Y=352|Justification=8|Color=8388608|FontID=1|Text=55
|RECORD=4|OwnerIndex=428|IsNotAccesible=T|IndexInSheet=95|OwnerPartId=1|Location.X=403|Location.Y=332|Justification=8|Color=8388608|FontID=1|Text=57
|RECORD=4|OwnerIndex=428|IsNotAccesible=T|IndexInSheet=96|OwnerPartId=1|Location.X=403|Location.Y=312|Justification=8|Color=8388608|FontID=1|Text=59
|RECORD=4|OwnerIndex=428|IsNotAccesible=T|IndexInSheet=97|OwnerPartId=1|Location.X=403|Location.Y=292|Justification=8|Color=8388608|FontID=1|Text=61
|RECORD=4|OwnerIndex=428|IsNotAccesible=T|IndexInSheet=98|OwnerPartId=1|Location.X=403|Location.Y=272|Justification=8|Color=8388608|FontID=1|Text=63
|RECORD=4|OwnerIndex=428|IsNotAccesible=T|IndexInSheet=99|OwnerPartId=1|Location.X=403|Location.Y=252|Justification=8|Color=8388608|FontID=1|Text=65
|RECORD=4|OwnerIndex=428|IsNotAccesible=T|IndexInSheet=100|OwnerPartId=1|Location.X=403|Location.Y=232|Justification=8|Color=8388608|FontID=1|Text=67
|RECORD=4|OwnerIndex=428|IsNotAccesible=T|IndexInSheet=101|OwnerPartId=1|Location.X=403|Location.Y=212|Justification=8|Color=8388608|FontID=1|Text=69
|RECORD=4|OwnerIndex=428|IsNotAccesible=T|IndexInSheet=102|OwnerPartId=1|Location.X=403|Location.Y=192|Justification=8|Color=8388608|FontID=1|Text=71
|RECORD=4|OwnerIndex=428|IsNotAccesible=T|IndexInSheet=103|OwnerPartId=1|Location.X=403|Location.Y=172|Justification=8|Color=8388608|FontID=1|Text=73
|RECORD=4|OwnerIndex=428|IsNotAccesible=T|IndexInSheet=104|OwnerPartId=1|Location.X=403|Location.Y=152|Justification=8|Color=8388608|FontID=1|Text=75
|RECORD=4|OwnerIndex=428|IsNotAccesible=T|IndexInSheet=105|OwnerPartId=1|Location.X=403|Location.Y=132|Justification=8|Color=8388608|FontID=1|Text=MNT 2
|RECORD=2|OwnerIndex=428|OwnerPartId=1|Electrical=4|PinConglomerate=48|PinLength=20|Location.X=410|Location.Y=800|Name=1|Designator=1|PinName_PositionConglomerate=16|Name_CustomFontID=1|PinDesignator_PositionConglomerate=16|Designator_CustomFontID=1|PinPropagationDelay=0.000000E+000
|RECORD=2|OwnerIndex=428|OwnerPartId=1|Electrical=4|PinConglomerate=48|PinLength=20|Location.X=410|Location.Y=780|Name=3|Designator=3|PinName_PositionConglomerate=16|Name_CustomFontID=1|PinDesignator_PositionConglomerate=16|Designator_CustomFontID=1|PinPropagationDelay=0.000000E+000
|RECORD=2|OwnerIndex=428|OwnerPartId=1|Electrical=4|PinConglomerate=48|PinLength=20|Location.X=410|Location.Y=760|Name=5|Designator=5|PinName_PositionConglomerate=16|Name_CustomFontID=1|PinDesignator_PositionConglomerate=16|Designator_CustomFontID=1|PinPropagationDelay=0.000000E+000
|RECORD=2|OwnerIndex=428|OwnerPartId=1|Electrical=4|PinConglomerate=48|PinLength=20|Location.X=410|Location.Y=740|Name=7|Designator=7|PinName_PositionConglomerate=16|Name_CustomFontID=1|PinDesignator_PositionConglomerate=16|Designator_CustomFontID=1|PinPropagationDelay=0.000000E+000
|RECORD=2|OwnerIndex=428|OwnerPartId=1|Electrical=4|PinConglomerate=48|PinLength=20|Location.X=410|Location.Y=720|Name=9|Designator=9|PinName_PositionConglomerate=16|Name_CustomFontID=1|PinDesignator_PositionConglomerate=16|Designator_CustomFontID=1|PinPropagationDelay=0.000000E+000
|RECORD=2|OwnerIndex=428|OwnerPartId=1|Electrical=4|PinConglomerate=48|PinLength=20|Location.X=410|Location.Y=700|Name=11|Designator=11|PinName_PositionConglomerate=16|Name_CustomFontID=1|PinDesignator_PositionConglomerate=16|Designator_CustomFontID=1|PinPropagationDelay=0.000000E+000
|RECORD=2|OwnerIndex=428|OwnerPartId=1|Electrical=4|PinConglomerate=48|PinLength=20|Location.X=410|Location.Y=680|Name=21|Designator=21|PinName_PositionConglomerate=16|Name_CustomFontID=1|PinDesignator_PositionConglomerate=16|Designator_CustomFontID=1|PinPropagationDelay=0.000000E+000
|RECORD=2|OwnerIndex=428|OwnerPartId=1|Electrical=4|PinConglomerate=48|PinLength=20|Location.X=410|Location.Y=660|Name=23|Designator=23|PinName_PositionConglomerate=16|Name_CustomFontID=1|PinDesignator_PositionConglomerate=16|Designator_CustomFontID=1|PinPropagationDelay=0.000000E+000
|RECORD=2|OwnerIndex=428|OwnerPartId=1|Electrical=4|PinConglomerate=48|PinLength=20|Location.X=410|Location.Y=640|Name=25|Designator=25|PinName_PositionConglomerate=16|Name_CustomFontID=1|PinDesignator_PositionConglomerate=16|Designator_CustomFontID=1|PinPropagationDelay=0.000000E+000
|RECORD=2|OwnerIndex=428|OwnerPartId=1|Electrical=4|PinConglomerate=48|PinLength=20|Location.X=410|Location.Y=620|Name=27|Designator=27|PinName_PositionConglomerate=16|Name_CustomFontID=1|PinDesignator_PositionConglomerate=16|Designator_CustomFontID=1|PinPropagationDelay=0.000000E+000
|RECORD=2|OwnerIndex=428|OwnerPartId=1|Electrical=4|PinConglomerate=48|PinLength=20|Location.X=410|Location.Y=600|Name=29|Designator=29|PinName_PositionConglomerate=16|Name_CustomFontID=1|PinDesignator_PositionConglomerate=16|Designator_CustomFontID=1|PinPropagationDelay=0.000000E+000
|RECORD=2|OwnerIndex=428|OwnerPartId=1|Electrical=4|PinConglomerate=48|PinLength=20|Location.X=410|Location.Y=580|Name=31|Designator=31|PinName_PositionConglomerate=16|Name_CustomFontID=1|PinDesignator_PositionConglomerate=16|Designator_CustomFontID=1|PinPropagationDelay=0.000000E+000
|RECORD=2|OwnerIndex=428|OwnerPartId=1|Electrical=4|PinConglomerate=48|PinLength=20|Location.X=410|Location.Y=560|Name=33|Designator=33|PinName_PositionConglomerate=16|Name_CustomFontID=1|PinDesignator_PositionConglomerate=16|Designator_CustomFontID=1|PinPropagationDelay=0.000000E+000
|RECORD=2|OwnerIndex=428|OwnerPartId=1|Electrical=4|PinConglomerate=48|PinLength=20|Location.X=410|Location.Y=540|Name=35|Designator=35|PinName_PositionConglomerate=16|Name_CustomFontID=1|PinDesignator_PositionConglomerate=16|Designator_CustomFontID=1|PinPropagationDelay=0.000000E+000
|RECORD=2|OwnerIndex=428|OwnerPartId=1|Electrical=4|PinConglomerate=48|PinLength=20|Location.X=410|Location.Y=520|Name=37|Designator=37|PinName_PositionConglomerate=16|Name_CustomFontID=1|PinDesignator_PositionConglomerate=16|Designator_CustomFontID=1|PinPropagationDelay=0.000000E+000
|RECORD=2|OwnerIndex=428|OwnerPartId=1|Electrical=4|PinConglomerate=48|PinLength=20|Location.X=410|Location.Y=500|Name=39|Designator=39|PinName_PositionConglomerate=16|Name_CustomFontID=1|PinDesignator_PositionConglomerate=16|Designator_CustomFontID=1|PinPropagationDelay=0.000000E+000
|RECORD=2|OwnerIndex=428|OwnerPartId=1|Electrical=4|PinConglomerate=48|PinLength=20|Location.X=410|Location.Y=480|Name=41|Designator=41|PinName_PositionConglomerate=16|Name_CustomFontID=1|PinDesignator_PositionConglomerate=16|Designator_CustomFontID=1|PinPropagationDelay=0.000000E+000
|RECORD=2|OwnerIndex=428|OwnerPartId=1|Electrical=4|PinConglomerate=48|PinLength=20|Location.X=410|Location.Y=460|Name=43|Designator=43|PinName_PositionConglomerate=16|Name_CustomFontID=1|PinDesignator_PositionConglomerate=16|Designator_CustomFontID=1|PinPropagationDelay=0.000000E+000
|RECORD=2|OwnerIndex=428|OwnerPartId=1|Electrical=4|PinConglomerate=48|PinLength=20|Location.X=410|Location.Y=440|Name=45|Designator=45|PinName_PositionConglomerate=16|Name_CustomFontID=1|PinDesignator_PositionConglomerate=16|Designator_CustomFontID=1|PinPropagationDelay=0.000000E+000
|RECORD=2|OwnerIndex=428|OwnerPartId=1|Electrical=4|PinConglomerate=48|PinLength=20|Location.X=410|Location.Y=420|Name=47|Designator=47|PinName_PositionConglomerate=16|Name_CustomFontID=1|PinDesignator_PositionConglomerate=16|Designator_CustomFontID=1|PinPropagationDelay=0.000000E+000
|RECORD=2|OwnerIndex=428|OwnerPartId=1|Electrical=4|PinConglomerate=48|PinLength=20|Location.X=410|Location.Y=400|Name=49|Designator=49|PinName_PositionConglomerate=16|Name_CustomFontID=1|PinDesignator_PositionConglomerate=16|Designator_CustomFontID=1|PinPropagationDelay=0.000000E+000
|RECORD=2|OwnerIndex=428|OwnerPartId=1|Electrical=4|PinConglomerate=48|PinLength=20|Location.X=410|Location.Y=380|Name=51|Designator=51|PinName_PositionConglomerate=16|Name_CustomFontID=1|PinDesignator_PositionConglomerate=16|Designator_CustomFontID=1|PinPropagationDelay=0.000000E+000
|RECORD=2|OwnerIndex=428|OwnerPartId=1|Electrical=4|PinConglomerate=48|PinLength=20|Location.X=410|Location.Y=360|Name=53|Designator=53|PinName_PositionConglomerate=16|Name_CustomFontID=1|PinDesignator_PositionConglomerate=16|Designator_CustomFontID=1|PinPropagationDelay=0.000000E+000
|RECORD=2|OwnerIndex=428|OwnerPartId=1|Electrical=4|PinConglomerate=48|PinLength=20|Location.X=410|Location.Y=340|Name=55|Designator=55|PinName_PositionConglomerate=16|Name_CustomFontID=1|PinDesignator_PositionConglomerate=16|Designator_CustomFontID=1|PinPropagationDelay=0.000000E+000
|RECORD=2|OwnerIndex=428|OwnerPartId=1|Electrical=4|PinConglomerate=48|PinLength=20|Location.X=410|Location.Y=320|Name=57|Designator=57|PinName_PositionConglomerate=16|Name_CustomFontID=1|PinDesignator_PositionConglomerate=16|Designator_CustomFontID=1|PinPropagationDelay=0.000000E+000
|RECORD=2|OwnerIndex=428|OwnerPartId=1|Electrical=4|PinConglomerate=48|PinLength=20|Location.X=410|Location.Y=300|Name=59|Designator=59|PinName_PositionConglomerate=16|Name_CustomFontID=1|PinDesignator_PositionConglomerate=16|Designator_CustomFontID=1|PinPropagationDelay=0.000000E+000
|RECORD=2|OwnerIndex=428|OwnerPartId=1|Electrical=4|PinConglomerate=48|PinLength=20|Location.X=410|Location.Y=280|Name=61|Designator=61|PinName_PositionConglomerate=16|Name_CustomFontID=1|PinDesignator_PositionConglomerate=16|Designator_CustomFontID=1|PinPropagationDelay=0.000000E+000
|RECORD=2|OwnerIndex=428|OwnerPartId=1|Electrical=4|PinConglomerate=48|PinLength=20|Location.X=410|Location.Y=260|Name=63|Designator=63|PinName_PositionConglomerate=16|Name_CustomFontID=1|PinDesignator_PositionConglomerate=16|Designator_CustomFontID=1|PinPropagationDelay=0.000000E+000
|RECORD=2|OwnerIndex=428|OwnerPartId=1|Electrical=4|PinConglomerate=48|PinLength=20|Location.X=410|Location.Y=240|Name=65|Designator=65|PinName_PositionConglomerate=16|Name_CustomFontID=1|PinDesignator_PositionConglomerate=16|Designator_CustomFontID=1|PinPropagationDelay=0.000000E+000
|RECORD=2|OwnerIndex=428|OwnerPartId=1|Electrical=4|PinConglomerate=48|PinLength=20|Location.X=410|Location.Y=220|Name=67|Designator=67|PinName_PositionConglomerate=16|Name_CustomFontID=1|PinDesignator_PositionConglomerate=16|Designator_CustomFontID=1|PinPropagationDelay=0.000000E+000
|RECORD=2|OwnerIndex=428|OwnerPartId=1|Electrical=4|PinConglomerate=48|PinLength=20|Location.X=410|Location.Y=200|Name=69|Designator=69|PinName_PositionConglomerate=16|Name_CustomFontID=1|PinDesignator_PositionConglomerate=16|Designator_CustomFontID=1|PinPropagationDelay=0.000000E+000
|RECORD=2|OwnerIndex=428|OwnerPartId=1|Electrical=4|PinConglomerate=48|PinLength=20|Location.X=410|Location.Y=180|Name=71|Designator=71|PinName_PositionConglomerate=16|Name_CustomFontID=1|PinDesignator_PositionConglomerate=16|Designator_CustomFontID=1|PinPropagationDelay=0.000000E+000
|RECORD=2|OwnerIndex=428|OwnerPartId=1|Electrical=4|PinConglomerate=48|PinLength=20|Location.X=410|Location.Y=160|Name=73|Designator=73|PinName_PositionConglomerate=16|Name_CustomFontID=1|PinDesignator_PositionConglomerate=16|Designator_CustomFontID=1|PinPropagationDelay=0.000000E+000
|RECORD=2|OwnerIndex=428|OwnerPartId=1|Electrical=4|PinConglomerate=48|PinLength=20|Location.X=410|Location.Y=140|Name=75|Designator=75|PinName_PositionConglomerate=16|Name_CustomFontID=1|PinDesignator_PositionConglomerate=16|Designator_CustomFontID=1|PinPropagationDelay=0.000000E+000
|RECORD=2|OwnerIndex=428|OwnerPartId=1|Electrical=4|PinConglomerate=48|PinLength=20|Location.X=410|Location.Y=120|Name=MNT 2|Designator=77|PinName_PositionConglomerate=16|Name_CustomFontID=1|PinDesignator_PositionConglomerate=16|Designator_CustomFontID=1|PinPropagationDelay=0.000000E+000
|RECORD=14|OwnerIndex=428|IsNotAccesible=T|IndexInSheet=141|OwnerPartId=2|Location.X=360|Location.Y=120|Corner.X=410|Corner.Y=820|LineWidth=1|Color=128|AreaColor=11599871|IsSolid=T
|RECORD=8|OwnerIndex=428|IsNotAccesible=T|IndexInSheet=142|OwnerPartId=2|Location.X=385|Location.Y=800|Radius=3|SecondaryRadius=3|LineWidth=1|Color=16711680
|RECORD=13|OwnerIndex=428|IsNotAccesible=T|IndexInSheet=143|OwnerPartId=2|Location.X=388|Location.Y=800|Corner.X=410|Corner.Y=800|LineWidth=1|Color=16711680
|RECORD=8|OwnerIndex=428|IsNotAccesible=T|IndexInSheet=144|OwnerPartId=2|Location.X=385|Location.Y=780|Radius=3|SecondaryRadius=3|LineWidth=1|Color=16711680
|RECORD=13|OwnerIndex=428|IsNotAccesible=T|IndexInSheet=145|OwnerPartId=2|Location.X=388|Location.Y=780|Corner.X=410|Corner.Y=780|LineWidth=1|Color=16711680
|RECORD=8|OwnerIndex=428|IsNotAccesible=T|IndexInSheet=146|OwnerPartId=2|Location.X=385|Location.Y=760|Radius=3|SecondaryRadius=3|LineWidth=1|Color=16711680
|RECORD=13|OwnerIndex=428|IsNotAccesible=T|IndexInSheet=147|OwnerPartId=2|Location.X=388|Location.Y=760|Corner.X=410|Corner.Y=760|LineWidth=1|Color=16711680
|RECORD=8|OwnerIndex=428|IsNotAccesible=T|IndexInSheet=148|OwnerPartId=2|Location.X=385|Location.Y=740|Radius=3|SecondaryRadius=3|LineWidth=1|Color=16711680
|RECORD=13|OwnerIndex=428|IsNotAccesible=T|IndexInSheet=149|OwnerPartId=2|Location.X=388|Location.Y=740|Corner.X=410|Corner.Y=740|LineWidth=1|Color=16711680
|RECORD=8|OwnerIndex=428|IsNotAccesible=T|IndexInSheet=150|OwnerPartId=2|Location.X=385|Location.Y=720|Radius=3|SecondaryRadius=3|LineWidth=1|Color=16711680
|RECORD=13|OwnerIndex=428|IsNotAccesible=T|IndexInSheet=151|OwnerPartId=2|Location.X=388|Location.Y=720|Corner.X=410|Corner.Y=720|LineWidth=1|Color=16711680
|RECORD=8|OwnerIndex=428|IsNotAccesible=T|IndexInSheet=152|OwnerPartId=2|Location.X=385|Location.Y=700|Radius=3|SecondaryRadius=3|LineWidth=1|Color=16711680
|RECORD=13|OwnerIndex=428|IsNotAccesible=T|IndexInSheet=153|OwnerPartId=2|Location.X=388|Location.Y=700|Corner.X=410|Corner.Y=700|LineWidth=1|Color=16711680
|RECORD=8|OwnerIndex=428|IsNotAccesible=T|IndexInSheet=154|OwnerPartId=2|Location.X=385|Location.Y=680|Radius=3|SecondaryRadius=3|LineWidth=1|Color=16711680
|RECORD=13|OwnerIndex=428|IsNotAccesible=T|IndexInSheet=155|OwnerPartId=2|Location.X=388|Location.Y=680|Corner.X=410|Corner.Y=680|LineWidth=1|Color=16711680
|RECORD=8|OwnerIndex=428|IsNotAccesible=T|IndexInSheet=156|OwnerPartId=2|Location.X=385|Location.Y=660|Radius=3|SecondaryRadius=3|LineWidth=1|Color=16711680
|RECORD=13|OwnerIndex=428|IsNotAccesible=T|IndexInSheet=157|OwnerPartId=2|Location.X=388|Location.Y=660|Corner.X=410|Corner.Y=660|LineWidth=1|Color=16711680
|RECORD=8|OwnerIndex=428|IsNotAccesible=T|IndexInSheet=158|OwnerPartId=2|Location.X=385|Location.Y=640|Radius=3|SecondaryRadius=3|LineWidth=1|Color=16711680
|RECORD=13|OwnerIndex=428|IsNotAccesible=T|IndexInSheet=159|OwnerPartId=2|Location.X=388|Location.Y=640|Corner.X=410|Corner.Y=640|LineWidth=1|Color=16711680
|RECORD=8|OwnerIndex=428|IsNotAccesible=T|IndexInSheet=160|OwnerPartId=2|Location.X=385|Location.Y=620|Radius=3|SecondaryRadius=3|LineWidth=1|Color=16711680
|RECORD=13|OwnerIndex=428|IsNotAccesible=T|IndexInSheet=161|OwnerPartId=2|Location.X=388|Location.Y=620|Corner.X=410|Corner.Y=620|LineWidth=1|Color=16711680
|RECORD=8|OwnerIndex=428|IsNotAccesible=T|IndexInSheet=162|OwnerPartId=2|Location.X=385|Location.Y=600|Radius=3|SecondaryRadius=3|LineWidth=1|Color=16711680
|RECORD=13|OwnerIndex=428|IsNotAccesible=T|IndexInSheet=163|OwnerPartId=2|Location.X=388|Location.Y=600|Corner.X=410|Corner.Y=600|LineWidth=1|Color=16711680
|RECORD=8|OwnerIndex=428|IsNotAccesible=T|IndexInSheet=164|OwnerPartId=2|Location.X=385|Location.Y=580|Radius=3|SecondaryRadius=3|LineWidth=1|Color=16711680
|RECORD=13|OwnerIndex=428|IsNotAccesible=T|IndexInSheet=165|OwnerPartId=2|Location.X=388|Location.Y=580|Corner.X=410|Corner.Y=580|LineWidth=1|Color=16711680
|RECORD=8|OwnerIndex=428|IsNotAccesible=T|IndexInSheet=166|OwnerPartId=2|Location.X=385|Location.Y=560|Radius=3|SecondaryRadius=3|LineWidth=1|Color=16711680
|RECORD=13|OwnerIndex=428|IsNotAccesible=T|IndexInSheet=167|OwnerPartId=2|Location.X=388|Location.Y=560|Corner.X=410|Corner.Y=560|LineWidth=1|Color=16711680
|RECORD=8|OwnerIndex=428|IsNotAccesible=T|IndexInSheet=168|OwnerPartId=2|Location.X=385|Location.Y=540|Radius=3|SecondaryRadius=3|LineWidth=1|Color=16711680
|RECORD=13|OwnerIndex=428|IsNotAccesible=T|IndexInSheet=169|OwnerPartId=2|Location.X=388|Location.Y=540|Corner.X=410|Corner.Y=540|LineWidth=1|Color=16711680
|RECORD=8|OwnerIndex=428|IsNotAccesible=T|IndexInSheet=170|OwnerPartId=2|Location.X=385|Location.Y=520|Radius=3|SecondaryRadius=3|LineWidth=1|Color=16711680
|RECORD=13|OwnerIndex=428|IsNotAccesible=T|IndexInSheet=171|OwnerPartId=2|Location.X=388|Location.Y=520|Corner.X=410|Corner.Y=520|LineWidth=1|Color=16711680
|RECORD=8|OwnerIndex=428|IsNotAccesible=T|IndexInSheet=172|OwnerPartId=2|Location.X=385|Location.Y=500|Radius=3|SecondaryRadius=3|LineWidth=1|Color=16711680
|RECORD=13|OwnerIndex=428|IsNotAccesible=T|IndexInSheet=173|OwnerPartId=2|Location.X=388|Location.Y=500|Corner.X=410|Corner.Y=500|LineWidth=1|Color=16711680
|RECORD=8|OwnerIndex=428|IsNotAccesible=T|IndexInSheet=174|OwnerPartId=2|Location.X=385|Location.Y=480|Radius=3|SecondaryRadius=3|LineWidth=1|Color=16711680
|RECORD=13|OwnerIndex=428|IsNotAccesible=T|IndexInSheet=175|OwnerPartId=2|Location.X=388|Location.Y=480|Corner.X=410|Corner.Y=480|LineWidth=1|Color=16711680
|RECORD=8|OwnerIndex=428|IsNotAccesible=T|IndexInSheet=176|OwnerPartId=2|Location.X=385|Location.Y=460|Radius=3|SecondaryRadius=3|LineWidth=1|Color=16711680
|RECORD=13|OwnerIndex=428|IsNotAccesible=T|IndexInSheet=177|OwnerPartId=2|Location.X=388|Location.Y=460|Corner.X=410|Corner.Y=460|LineWidth=1|Color=16711680
|RECORD=8|OwnerIndex=428|IsNotAccesible=T|IndexInSheet=178|OwnerPartId=2|Location.X=385|Location.Y=440|Radius=3|SecondaryRadius=3|LineWidth=1|Color=16711680
|RECORD=13|OwnerIndex=428|IsNotAccesible=T|IndexInSheet=179|OwnerPartId=2|Location.X=388|Location.Y=440|Corner.X=410|Corner.Y=440|LineWidth=1|Color=16711680
|RECORD=8|OwnerIndex=428|IsNotAccesible=T|IndexInSheet=180|OwnerPartId=2|Location.X=385|Location.Y=420|Radius=3|SecondaryRadius=3|LineWidth=1|Color=16711680
|RECORD=13|OwnerIndex=428|IsNotAccesible=T|IndexInSheet=181|OwnerPartId=2|Location.X=388|Location.Y=420|Corner.X=410|Corner.Y=420|LineWidth=1|Color=16711680
|RECORD=8|OwnerIndex=428|IsNotAccesible=T|IndexInSheet=182|OwnerPartId=2|Location.X=385|Location.Y=400|Radius=3|SecondaryRadius=3|LineWidth=1|Color=16711680
|RECORD=13|OwnerIndex=428|IsNotAccesible=T|IndexInSheet=183|OwnerPartId=2|Location.X=388|Location.Y=400|Corner.X=410|Corner.Y=400|LineWidth=1|Color=16711680
|RECORD=8|OwnerIndex=428|IsNotAccesible=T|IndexInSheet=184|OwnerPartId=2|Location.X=385|Location.Y=380|Radius=3|SecondaryRadius=3|LineWidth=1|Color=16711680
|RECORD=13|OwnerIndex=428|IsNotAccesible=T|IndexInSheet=185|OwnerPartId=2|Location.X=388|Location.Y=380|Corner.X=410|Corner.Y=380|LineWidth=1|Color=16711680
|RECORD=8|OwnerIndex=428|IsNotAccesible=T|IndexInSheet=186|OwnerPartId=2|Location.X=385|Location.Y=360|Radius=3|SecondaryRadius=3|LineWidth=1|Color=16711680
|RECORD=13|OwnerIndex=428|IsNotAccesible=T|IndexInSheet=187|OwnerPartId=2|Location.X=388|Location.Y=360|Corner.X=410|Corner.Y=360|LineWidth=1|Color=16711680
|RECORD=8|OwnerIndex=428|IsNotAccesible=T|IndexInSheet=188|OwnerPartId=2|Location.X=385|Location.Y=340|Radius=3|SecondaryRadius=3|LineWidth=1|Color=16711680
|RECORD=13|OwnerIndex=428|IsNotAccesible=T|IndexInSheet=189|OwnerPartId=2|Location.X=388|Location.Y=340|Corner.X=410|Corner.Y=340|LineWidth=1|Color=16711680
|RECORD=8|OwnerIndex=428|IsNotAccesible=T|IndexInSheet=190|OwnerPartId=2|Location.X=385|Location.Y=320|Radius=3|SecondaryRadius=3|LineWidth=1|Color=16711680
|RECORD=13|OwnerIndex=428|IsNotAccesible=T|IndexInSheet=191|OwnerPartId=2|Location.X=388|Location.Y=320|Corner.X=410|Corner.Y=320|LineWidth=1|Color=16711680
|RECORD=8|OwnerIndex=428|IsNotAccesible=T|IndexInSheet=192|OwnerPartId=2|Location.X=385|Location.Y=300|Radius=3|SecondaryRadius=3|LineWidth=1|Color=16711680
|RECORD=13|OwnerIndex=428|IsNotAccesible=T|IndexInSheet=193|OwnerPartId=2|Location.X=388|Location.Y=300|Corner.X=410|Corner.Y=300|LineWidth=1|Color=16711680
|RECORD=8|OwnerIndex=428|IsNotAccesible=T|IndexInSheet=194|OwnerPartId=2|Location.X=385|Location.Y=280|Radius=3|SecondaryRadius=3|LineWidth=1|Color=16711680
|RECORD=13|OwnerIndex=428|IsNotAccesible=T|IndexInSheet=195|OwnerPartId=2|Location.X=388|Location.Y=280|Corner.X=410|Corner.Y=280|LineWidth=1|Color=16711680
|RECORD=8|OwnerIndex=428|IsNotAccesible=T|IndexInSheet=196|OwnerPartId=2|Location.X=385|Location.Y=260|Radius=3|SecondaryRadius=3|LineWidth=1|Color=16711680
|RECORD=13|OwnerIndex=428|IsNotAccesible=T|IndexInSheet=197|OwnerPartId=2|Location.X=388|Location.Y=260|Corner.X=410|Corner.Y=260|LineWidth=1|Color=16711680
|RECORD=8|OwnerIndex=428|IsNotAccesible=T|IndexInSheet=198|OwnerPartId=2|Location.X=385|Location.Y=240|Radius=3|SecondaryRadius=3|LineWidth=1|Color=16711680
|RECORD=13|OwnerIndex=428|IsNotAccesible=T|IndexInSheet=199|OwnerPartId=2|Location.X=388|Location.Y=240|Corner.X=410|Corner.Y=240|LineWidth=1|Color=16711680
|RECORD=8|OwnerIndex=428|IsNotAccesible=T|IndexInSheet=200|OwnerPartId=2|Location.X=385|Location.Y=220|Radius=3|SecondaryRadius=3|LineWidth=1|Color=16711680
|RECORD=13|OwnerIndex=428|IsNotAccesible=T|IndexInSheet=201|OwnerPartId=2|Location.X=388|Location.Y=220|Corner.X=410|Corner.Y=220|LineWidth=1|Color=16711680
|RECORD=8|OwnerIndex=428|IsNotAccesible=T|IndexInSheet=202|OwnerPartId=2|Location.X=385|Location.Y=200|Radius=3|SecondaryRadius=3|LineWidth=1|Color=16711680
|RECORD=13|OwnerIndex=428|IsNotAccesible=T|IndexInSheet=203|OwnerPartId=2|Location.X=388|Location.Y=200|Corner.X=410|Corner.Y=200|LineWidth=1|Color=16711680
|RECORD=8|OwnerIndex=428|IsNotAccesible=T|IndexInSheet=204|OwnerPartId=2|Location.X=385|Location.Y=180|Radius=3|SecondaryRadius=3|LineWidth=1|Color=16711680
|RECORD=13|OwnerIndex=428|IsNotAccesible=T|IndexInSheet=205|OwnerPartId=2|Location.X=388|Location.Y=180|Corner.X=410|Corner.Y=180|LineWidth=1|Color=16711680
|RECORD=8|OwnerIndex=428|IsNotAccesible=T|IndexInSheet=206|OwnerPartId=2|Location.X=385|Location.Y=160|Radius=3|SecondaryRadius=3|LineWidth=1|Color=16711680
|RECORD=13|OwnerIndex=428|IsNotAccesible=T|IndexInSheet=207|OwnerPartId=2|Location.X=388|Location.Y=160|Corner.X=410|Corner.Y=160|LineWidth=1|Color=16711680
|RECORD=8|OwnerIndex=428|IsNotAccesible=T|IndexInSheet=208|OwnerPartId=2|Location.X=385|Location.Y=140|Radius=3|SecondaryRadius=3|LineWidth=1|Color=16711680
|RECORD=13|OwnerIndex=428|IsNotAccesible=T|IndexInSheet=209|OwnerPartId=2|Location.X=388|Location.Y=140|Corner.X=410|Corner.Y=140|LineWidth=1|Color=16711680
|RECORD=4|OwnerIndex=428|IsNotAccesible=T|IndexInSheet=210|OwnerPartId=2|Location.X=403|Location.Y=812|Justification=8|Color=8388608|FontID=1|Text=2
|RECORD=4|OwnerIndex=428|IsNotAccesible=T|IndexInSheet=211|OwnerPartId=2|Location.X=403|Location.Y=792|Justification=8|Color=8388608|FontID=1|Text=4
|RECORD=4|OwnerIndex=428|IsNotAccesible=T|IndexInSheet=212|OwnerPartId=2|Location.X=403|Location.Y=772|Justification=8|Color=8388608|FontID=1|Text=6
|RECORD=4|OwnerIndex=428|IsNotAccesible=T|IndexInSheet=213|OwnerPartId=2|Location.X=403|Location.Y=752|Justification=8|Color=8388608|FontID=1|Text=8
|RECORD=4|OwnerIndex=428|IsNotAccesible=T|IndexInSheet=214|OwnerPartId=2|Location.X=403|Location.Y=732|Justification=8|Color=8388608|FontID=1|Text=10
|RECORD=4|OwnerIndex=428|IsNotAccesible=T|IndexInSheet=215|OwnerPartId=2|Location.X=403|Location.Y=712|Justification=8|Color=8388608|FontID=1|Text=20
|RECORD=4|OwnerIndex=428|IsNotAccesible=T|IndexInSheet=216|OwnerPartId=2|Location.X=403|Location.Y=692|Justification=8|Color=8388608|FontID=1|Text=22
|RECORD=4|OwnerIndex=428|IsNotAccesible=T|IndexInSheet=217|OwnerPartId=2|Location.X=403|Location.Y=672|Justification=8|Color=8388608|FontID=1|Text=24
|RECORD=4|OwnerIndex=428|IsNotAccesible=T|IndexInSheet=218|OwnerPartId=2|Location.X=403|Location.Y=652|Justification=8|Color=8388608|FontID=1|Text=26
|RECORD=4|OwnerIndex=428|IsNotAccesible=T|IndexInSheet=219|OwnerPartId=2|Location.X=403|Location.Y=632|Justification=8|Color=8388608|FontID=1|Text=28
|RECORD=4|OwnerIndex=428|IsNotAccesible=T|IndexInSheet=220|OwnerPartId=2|Location.X=403|Location.Y=612|Justification=8|Color=8388608|FontID=1|Text=30
|RECORD=4|OwnerIndex=428|IsNotAccesible=T|IndexInSheet=221|OwnerPartId=2|Location.X=403|Location.Y=592|Justification=8|Color=8388608|FontID=1|Text=32
|RECORD=4|OwnerIndex=428|IsNotAccesible=T|IndexInSheet=222|OwnerPartId=2|Location.X=403|Location.Y=572|Justification=8|Color=8388608|FontID=1|Text=34
|RECORD=4|OwnerIndex=428|IsNotAccesible=T|IndexInSheet=223|OwnerPartId=2|Location.X=403|Location.Y=552|Justification=8|Color=8388608|FontID=1|Text=36
|RECORD=4|OwnerIndex=428|IsNotAccesible=T|IndexInSheet=224|OwnerPartId=2|Location.X=403|Location.Y=532|Justification=8|Color=8388608|FontID=1|Text=38
|RECORD=4|OwnerIndex=428|IsNotAccesible=T|IndexInSheet=225|OwnerPartId=2|Location.X=403|Location.Y=512|Justification=8|Color=8388608|FontID=1|Text=40
|RECORD=4|OwnerIndex=428|IsNotAccesible=T|IndexInSheet=226|OwnerPartId=2|Location.X=403|Location.Y=492|Justification=8|Color=8388608|FontID=1|Text=42
|RECORD=4|OwnerIndex=428|IsNotAccesible=T|IndexInSheet=227|OwnerPartId=2|Location.X=403|Location.Y=472|Justification=8|Color=8388608|FontID=1|Text=44
|RECORD=4|OwnerIndex=428|IsNotAccesible=T|IndexInSheet=228|OwnerPartId=2|Location.X=403|Location.Y=452|Justification=8|Color=8388608|FontID=1|Text=46
|RECORD=4|OwnerIndex=428|IsNotAccesible=T|IndexInSheet=229|OwnerPartId=2|Location.X=403|Location.Y=432|Justification=8|Color=8388608|FontID=1|Text=48
|RECORD=4|OwnerIndex=428|IsNotAccesible=T|IndexInSheet=230|OwnerPartId=2|Location.X=403|Location.Y=412|Justification=8|Color=8388608|FontID=1|Text=50
|RECORD=4|OwnerIndex=428|IsNotAccesible=T|IndexInSheet=231|OwnerPartId=2|Location.X=403|Location.Y=392|Justification=8|Color=8388608|FontID=1|Text=52
|RECORD=4|OwnerIndex=428|IsNotAccesible=T|IndexInSheet=232|OwnerPartId=2|Location.X=403|Location.Y=372|Justification=8|Color=8388608|FontID=1|Text=54
|RECORD=4|OwnerIndex=428|IsNotAccesible=T|IndexInSheet=233|OwnerPartId=2|Location.X=403|Location.Y=352|Justification=8|Color=8388608|FontID=1|Text=56
|RECORD=4|OwnerIndex=428|IsNotAccesible=T|IndexInSheet=234|OwnerPartId=2|Location.X=403|Location.Y=332|Justification=8|Color=8388608|FontID=1|Text=58
|RECORD=4|OwnerIndex=428|IsNotAccesible=T|IndexInSheet=235|OwnerPartId=2|Location.X=403|Location.Y=312|Justification=8|Color=8388608|FontID=1|Text=60
|RECORD=4|OwnerIndex=428|IsNotAccesible=T|IndexInSheet=236|OwnerPartId=2|Location.X=403|Location.Y=292|Justification=8|Color=8388608|FontID=1|Text=62
|RECORD=4|OwnerIndex=428|IsNotAccesible=T|IndexInSheet=237|OwnerPartId=2|Location.X=403|Location.Y=272|Justification=8|Color=8388608|FontID=1|Text=64
|RECORD=4|OwnerIndex=428|IsNotAccesible=T|IndexInSheet=238|OwnerPartId=2|Location.X=403|Location.Y=252|Justification=8|Color=8388608|FontID=1|Text=66
|RECORD=4|OwnerIndex=428|IsNotAccesible=T|IndexInSheet=239|OwnerPartId=2|Location.X=403|Location.Y=232|Justification=8|Color=8388608|FontID=1|Text=68
|RECORD=4|OwnerIndex=428|IsNotAccesible=T|IndexInSheet=240|OwnerPartId=2|Location.X=403|Location.Y=212|Justification=8|Color=8388608|FontID=1|Text=70
|RECORD=4|OwnerIndex=428|IsNotAccesible=T|IndexInSheet=241|OwnerPartId=2|Location.X=403|Location.Y=192|Justification=8|Color=8388608|FontID=1|Text=72
|RECORD=4|OwnerIndex=428|IsNotAccesible=T|IndexInSheet=242|OwnerPartId=2|Location.X=403|Location.Y=172|Justification=8|Color=8388608|FontID=1|Text=74
|RECORD=4|OwnerIndex=428|IsNotAccesible=T|IndexInSheet=243|OwnerPartId=2|Location.X=403|Location.Y=152|Justification=8|Color=8388608|FontID=1|Text=MNT 1
|RECORD=2|OwnerIndex=428|OwnerPartId=2|Electrical=4|PinConglomerate=48|PinLength=20|Location.X=410|Location.Y=800|Name=2|Designator=2|PinName_PositionConglomerate=16|Name_CustomFontID=1|PinDesignator_PositionConglomerate=16|Designator_CustomFontID=1|PinPropagationDelay=0.000000E+000
|RECORD=2|OwnerIndex=428|OwnerPartId=2|Electrical=4|PinConglomerate=48|PinLength=20|Location.X=410|Location.Y=780|Name=4|Designator=4|PinName_PositionConglomerate=16|Name_CustomFontID=1|PinDesignator_PositionConglomerate=16|Designator_CustomFontID=1|PinPropagationDelay=0.000000E+000
|RECORD=2|OwnerIndex=428|OwnerPartId=2|Electrical=4|PinConglomerate=48|PinLength=20|Location.X=410|Location.Y=760|Name=6|Designator=6|PinName_PositionConglomerate=16|Name_CustomFontID=1|PinDesignator_PositionConglomerate=16|Designator_CustomFontID=1|PinPropagationDelay=0.000000E+000
|RECORD=2|OwnerIndex=428|OwnerPartId=2|Electrical=4|PinConglomerate=48|PinLength=20|Location.X=410|Location.Y=740|Name=8|Designator=8|PinName_PositionConglomerate=16|Name_CustomFontID=1|PinDesignator_PositionConglomerate=16|Designator_CustomFontID=1|PinPropagationDelay=0.000000E+000
|RECORD=2|OwnerIndex=428|OwnerPartId=2|Electrical=4|PinConglomerate=48|PinLength=20|Location.X=410|Location.Y=720|Name=10|Designator=10|PinName_PositionConglomerate=16|Name_CustomFontID=1|PinDesignator_PositionConglomerate=16|Designator_CustomFontID=1|PinPropagationDelay=0.000000E+000
|RECORD=2|OwnerIndex=428|OwnerPartId=2|Electrical=4|PinConglomerate=48|PinLength=20|Location.X=410|Location.Y=700|Name=20|Designator=20|PinName_PositionConglomerate=16|Name_CustomFontID=1|PinDesignator_PositionConglomerate=16|Designator_CustomFontID=1|PinPropagationDelay=0.000000E+000
|RECORD=2|OwnerIndex=428|OwnerPartId=2|Electrical=4|PinConglomerate=48|PinLength=20|Location.X=410|Location.Y=680|Name=22|Designator=22|PinName_PositionConglomerate=16|Name_CustomFontID=1|PinDesignator_PositionConglomerate=16|Designator_CustomFontID=1|PinPropagationDelay=0.000000E+000
|RECORD=2|OwnerIndex=428|OwnerPartId=2|Electrical=4|PinConglomerate=48|PinLength=20|Location.X=410|Location.Y=660|Name=24|Designator=24|PinName_PositionConglomerate=16|Name_CustomFontID=1|PinDesignator_PositionConglomerate=16|Designator_CustomFontID=1|PinPropagationDelay=0.000000E+000
|RECORD=2|OwnerIndex=428|OwnerPartId=2|Electrical=4|PinConglomerate=48|PinLength=20|Location.X=410|Location.Y=640|Name=26|Designator=26|PinName_PositionConglomerate=16|Name_CustomFontID=1|PinDesignator_PositionConglomerate=16|Designator_CustomFontID=1|PinPropagationDelay=0.000000E+000
|RECORD=2|OwnerIndex=428|OwnerPartId=2|Electrical=4|PinConglomerate=48|PinLength=20|Location.X=410|Location.Y=620|Name=28|Designator=28|PinName_PositionConglomerate=16|Name_CustomFontID=1|PinDesignator_PositionConglomerate=16|Designator_CustomFontID=1|PinPropagationDelay=0.000000E+000
|RECORD=2|OwnerIndex=428|OwnerPartId=2|Electrical=4|PinConglomerate=48|PinLength=20|Location.X=410|Location.Y=600|Name=30|Designator=30|PinName_PositionConglomerate=16|Name_CustomFontID=1|PinDesignator_PositionConglomerate=16|Designator_CustomFontID=1|PinPropagationDelay=0.000000E+000
|RECORD=2|OwnerIndex=428|OwnerPartId=2|Electrical=4|PinConglomerate=48|PinLength=20|Location.X=410|Location.Y=580|Name=32|Designator=32|PinName_PositionConglomerate=16|Name_CustomFontID=1|PinDesignator_PositionConglomerate=16|Designator_CustomFontID=1|PinPropagationDelay=0.000000E+000
|RECORD=2|OwnerIndex=428|OwnerPartId=2|Electrical=4|PinConglomerate=48|PinLength=20|Location.X=410|Location.Y=560|Name=34|Designator=34|PinName_PositionConglomerate=16|Name_CustomFontID=1|PinDesignator_PositionConglomerate=16|Designator_CustomFontID=1|PinPropagationDelay=0.000000E+000
|RECORD=2|OwnerIndex=428|OwnerPartId=2|Electrical=4|PinConglomerate=48|PinLength=20|Location.X=410|Location.Y=540|Name=36|Designator=36|PinName_PositionConglomerate=16|Name_CustomFontID=1|PinDesignator_PositionConglomerate=16|Designator_CustomFontID=1|PinPropagationDelay=0.000000E+000
|RECORD=2|OwnerIndex=428|OwnerPartId=2|Electrical=4|PinConglomerate=48|PinLength=20|Location.X=410|Location.Y=520|Name=38|Designator=38|PinName_PositionConglomerate=16|Name_CustomFontID=1|PinDesignator_PositionConglomerate=16|Designator_CustomFontID=1|PinPropagationDelay=0.000000E+000
|RECORD=2|OwnerIndex=428|OwnerPartId=2|Electrical=4|PinConglomerate=48|PinLength=20|Location.X=410|Location.Y=500|Name=40|Designator=40|PinName_PositionConglomerate=16|Name_CustomFontID=1|PinDesignator_PositionConglomerate=16|Designator_CustomFontID=1|PinPropagationDelay=0.000000E+000
|RECORD=2|OwnerIndex=428|OwnerPartId=2|Electrical=4|PinConglomerate=48|PinLength=20|Location.X=410|Location.Y=480|Name=42|Designator=42|PinName_PositionConglomerate=16|Name_CustomFontID=1|PinDesignator_PositionConglomerate=16|Designator_CustomFontID=1|PinPropagationDelay=0.000000E+000
|RECORD=2|OwnerIndex=428|OwnerPartId=2|Electrical=4|PinConglomerate=48|PinLength=20|Location.X=410|Location.Y=460|Name=44|Designator=44|PinName_PositionConglomerate=16|Name_CustomFontID=1|PinDesignator_PositionConglomerate=16|Designator_CustomFontID=1|PinPropagationDelay=0.000000E+000
|RECORD=2|OwnerIndex=428|OwnerPartId=2|Electrical=4|PinConglomerate=48|PinLength=20|Location.X=410|Location.Y=440|Name=46|Designator=46|PinName_PositionConglomerate=16|Name_CustomFontID=1|PinDesignator_PositionConglomerate=16|Designator_CustomFontID=1|PinPropagationDelay=0.000000E+000
|RECORD=2|OwnerIndex=428|OwnerPartId=2|Electrical=4|PinConglomerate=48|PinLength=20|Location.X=410|Location.Y=420|Name=48|Designator=48|PinName_PositionConglomerate=16|Name_CustomFontID=1|PinDesignator_PositionConglomerate=16|Designator_CustomFontID=1|PinPropagationDelay=0.000000E+000
|RECORD=2|OwnerIndex=428|OwnerPartId=2|Electrical=4|PinConglomerate=48|PinLength=20|Location.X=410|Location.Y=400|Name=50|Designator=50|PinName_PositionConglomerate=16|Name_CustomFontID=1|PinDesignator_PositionConglomerate=16|Designator_CustomFontID=1|PinPropagationDelay=0.000000E+000
|RECORD=2|OwnerIndex=428|OwnerPartId=2|Electrical=4|PinConglomerate=48|PinLength=20|Location.X=410|Location.Y=380|Name=52|Designator=52|PinName_PositionConglomerate=16|Name_CustomFontID=1|PinDesignator_PositionConglomerate=16|Designator_CustomFontID=1|PinPropagationDelay=0.000000E+000
|RECORD=2|OwnerIndex=428|OwnerPartId=2|Electrical=4|PinConglomerate=48|PinLength=20|Location.X=410|Location.Y=360|Name=54|Designator=54|PinName_PositionConglomerate=16|Name_CustomFontID=1|PinDesignator_PositionConglomerate=16|Designator_CustomFontID=1|PinPropagationDelay=0.000000E+000
|RECORD=2|OwnerIndex=428|OwnerPartId=2|Electrical=4|PinConglomerate=48|PinLength=20|Location.X=410|Location.Y=340|Name=56|Designator=56|PinName_PositionConglomerate=16|Name_CustomFontID=1|PinDesignator_PositionConglomerate=16|Designator_CustomFontID=1|PinPropagationDelay=0.000000E+000
|RECORD=2|OwnerIndex=428|OwnerPartId=2|Electrical=4|PinConglomerate=48|PinLength=20|Location.X=410|Location.Y=320|Name=58|Designator=58|PinName_PositionConglomerate=16|Name_CustomFontID=1|PinDesignator_PositionConglomerate=16|Designator_CustomFontID=1|PinPropagationDelay=0.000000E+000
|RECORD=2|OwnerIndex=428|OwnerPartId=2|Electrical=4|PinConglomerate=48|PinLength=20|Location.X=410|Location.Y=300|Name=60|Designator=60|PinName_PositionConglomerate=16|Name_CustomFontID=1|PinDesignator_PositionConglomerate=16|Designator_CustomFontID=1|PinPropagationDelay=0.000000E+000
|RECORD=2|OwnerIndex=428|OwnerPartId=2|Electrical=4|PinConglomerate=48|PinLength=20|Location.X=410|Location.Y=280|Name=62|Designator=62|PinName_PositionConglomerate=16|Name_CustomFontID=1|PinDesignator_PositionConglomerate=16|Designator_CustomFontID=1|PinPropagationDelay=0.000000E+000
|RECORD=2|OwnerIndex=428|OwnerPartId=2|Electrical=4|PinConglomerate=48|PinLength=20|Location.X=410|Location.Y=260|Name=64|Designator=64|PinName_PositionConglomerate=16|Name_CustomFontID=1|PinDesignator_PositionConglomerate=16|Designator_CustomFontID=1|PinPropagationDelay=0.000000E+000
|RECORD=2|OwnerIndex=428|OwnerPartId=2|Electrical=4|PinConglomerate=48|PinLength=20|Location.X=410|Location.Y=240|Name=66|Designator=66|PinName_PositionConglomerate=16|Name_CustomFontID=1|PinDesignator_PositionConglomerate=16|Designator_CustomFontID=1|PinPropagationDelay=0.000000E+000
|RECORD=2|OwnerIndex=428|OwnerPartId=2|Electrical=4|PinConglomerate=48|PinLength=20|Location.X=410|Location.Y=220|Name=68|Designator=68|PinName_PositionConglomerate=16|Name_CustomFontID=1|PinDesignator_PositionConglomerate=16|Designator_CustomFontID=1|PinPropagationDelay=0.000000E+000
|RECORD=2|OwnerIndex=428|OwnerPartId=2|Electrical=4|PinConglomerate=48|PinLength=20|Location.X=410|Location.Y=200|Name=70|Designator=70|PinName_PositionConglomerate=16|Name_CustomFontID=1|PinDesignator_PositionConglomerate=16|Designator_CustomFontID=1|PinPropagationDelay=0.000000E+000
|RECORD=2|OwnerIndex=428|OwnerPartId=2|Electrical=4|PinConglomerate=48|PinLength=20|Location.X=410|Location.Y=180|Name=72|Designator=72|PinName_PositionConglomerate=16|Name_CustomFontID=1|PinDesignator_PositionConglomerate=16|Designator_CustomFontID=1|PinPropagationDelay=0.000000E+000
|RECORD=2|OwnerIndex=428|OwnerPartId=2|Electrical=4|PinConglomerate=48|PinLength=20|Location.X=410|Location.Y=160|Name=74|Designator=74|PinName_PositionConglomerate=16|Name_CustomFontID=1|PinDesignator_PositionConglomerate=16|Designator_CustomFontID=1|PinPropagationDelay=0.000000E+000
|RECORD=2|OwnerIndex=428|OwnerPartId=2|Electrical=4|PinConglomerate=48|PinLength=20|Location.X=410|Location.Y=140|Name=MNT 1|Designator=76|PinName_PositionConglomerate=16|Name_CustomFontID=1|PinDesignator_PositionConglomerate=16|Designator_CustomFontID=1|PinPropagationDelay=0.000000E+000
|RECORD=41|OwnerIndex=428|IndexInSheet=278|OwnerPartId=-1|Location.X=360|Location.Y=820|Color=8388608|FontID=1|IsHidden=T|Text=500mA|Name=Contact Current Rating
|RECORD=41|OwnerIndex=428|IndexInSheet=279|OwnerPartId=-1|Location.X=360|Location.Y=820|Color=8388608|FontID=1|IsHidden=T|Text=67|Name=Number of Contacts
|RECORD=41|OwnerIndex=428|IndexInSheet=280|OwnerPartId=-1|Location.X=360|Location.Y=820|Color=8388608|FontID=1|IsHidden=T|Text=Right Angle|Name=Orientation
|RECORD=41|OwnerIndex=428|IndexInSheet=281|OwnerPartId=-1|Location.X=360|Location.Y=820|Color=8388608|FontID=1|IsHidden=T|Text=0.862inch|Name=Length
|RECORD=41|OwnerIndex=428|IndexInSheet=282|OwnerPartId=-1|Location.X=360|Location.Y=820|Color=8388608|FontID=1|IsHidden=T|Text=No|Name=Radiation Hardening
|RECORD=41|OwnerIndex=428|IndexInSheet=283|OwnerPartId=-1|Location.X=360|Location.Y=820|Color=8388608|FontID=1|IsHidden=T|Text=Right Angle|Name=PCB Mounting Orientation
|RECORD=41|OwnerIndex=428|IndexInSheet=284|OwnerPartId=-1|Location.X=360|Location.Y=820|Color=8388608|FontID=1|IsHidden=T|Text=Surface Mount|Name=Mount
|RECORD=41|OwnerIndex=428|IndexInSheet=285|OwnerPartId=-1|Location.X=360|Location.Y=820|Color=8388608|FontID=1|IsHidden=T|Text=Gold|Name=Contact Plating
|RECORD=41|OwnerIndex=428|IndexInSheet=286|OwnerPartId=-1|Location.X=360|Location.Y=820|Color=8388608|FontID=1|IsHidden=T|Text=Copper Alloy|Name=Contact Material
|RECORD=41|OwnerIndex=428|IndexInSheet=287|OwnerPartId=-1|Location.X=360|Location.Y=820|Color=8388608|FontID=1|IsHidden=T|Text=8.7mm|Name=Width
|RECORD=41|OwnerIndex=428|IndexInSheet=288|OwnerPartId=-1|Location.X=360|Location.Y=820|Color=8388608|FontID=1|IsHidden=T|Text=2|Name=Number of Rows
|RECORD=41|OwnerIndex=428|IndexInSheet=289|OwnerPartId=-1|Location.X=360|Location.Y=820|Color=8388608|FontID=1|IsHidden=T|Text=Black|Name=Color
|RECORD=41|OwnerIndex=428|IndexInSheet=290|OwnerPartId=-1|Location.X=360|Location.Y=820|Color=8388608|FontID=1|IsHidden=T|Text=0.5mm|Name=Pitch
|RECORD=41|OwnerIndex=428|IndexInSheet=291|OwnerPartId=-1|Location.X=360|Location.Y=820|Color=8388608|FontID=1|IsHidden=T|Text=Compliant|Name=ELV
|RECORD=41|OwnerIndex=428|IndexInSheet=292|OwnerPartId=-1|Location.X=360|Location.Y=820|Color=8388608|FontID=1|IsHidden=T|Text=Black|Name=Housing Color
|RECORD=41|OwnerIndex=428|IndexInSheet=293|OwnerPartId=-1|Location.X=360|Location.Y=820|Color=8388608|FontID=1|IsHidden=T|Text=50V|Name=Voltage Rating
|RECORD=41|OwnerIndex=428|IndexInSheet=294|OwnerPartId=-1|Location.X=360|Location.Y=820|Color=8388608|FontID=1|IsHidden=T|Text=67|Name=Number of Positions
|RECORD=41|OwnerIndex=428|IndexInSheet=295|OwnerPartId=-1|Location.X=360|Location.Y=820|Color=8388608|FontID=1|IsHidden=T|Text=Thermoplastic|Name=Housing Material
|RECORD=41|OwnerIndex=428|IndexInSheet=296|OwnerPartId=-1|Location.X=360|Location.Y=820|Color=8388608|FontID=1|IsHidden=T|Text=Female|Name=Gender
|RECORD=41|OwnerIndex=428|IndexInSheet=297|OwnerPartId=-1|Location.X=360|Location.Y=820|Color=8388608|FontID=1|IsHidden=T|Text=-40°C|Name=Min Operating Temperature
|RECORD=41|OwnerIndex=428|IndexInSheet=298|OwnerPartId=-1|Location.X=360|Location.Y=820|Color=8388608|FontID=1|IsHidden=T|Text=80°C|Name=Max Operating Temperature
|RECORD=41|OwnerIndex=428|IndexInSheet=299|OwnerPartId=-1|Location.X=360|Location.Y=820|Color=8388608|FontID=1|IsHidden=T|Text=500MR|Name=Insulation Resistance
|RECORD=41|OwnerIndex=428|IndexInSheet=300|OwnerPartId=-1|Location.X=360|Location.Y=820|Color=8388608|FontID=1|IsHidden=T|Text=7.55mm|Name=Row Spacing
|RECORD=41|OwnerIndex=428|IndexInSheet=301|OwnerPartId=-1|Location.X=360|Location.Y=820|Color=8388608|FontID=1|IsHidden=T|Text=Yes|Name=RoHS Compliant
|RECORD=41|OwnerIndex=428|IndexInSheet=302|OwnerPartId=-1|Location.X=360|Location.Y=820|Color=8388608|FontID=1|IsHidden=T|Text=1200|Name=Package Quantity
|RECORD=41|OwnerIndex=428|IndexInSheet=303|OwnerPartId=-1|Location.X=360|Location.Y=820|Color=8388608|FontID=1|IsHidden=T|Text=Tape and Reel|Name=Packaging
|RECORD=41|OwnerIndex=428|IndexInSheet=304|OwnerPartId=-1|Location.X=360|Location.Y=820|Color=8388608|FontID=1|IsHidden=T|Text=3.2mm|Name=Height
|RECORD=41|OwnerIndex=428|IndexInSheet=305|OwnerPartId=-1|Location.X=360|Location.Y=820|Color=8388608|FontID=1|IsHidden=T|Text=Solder|Name=Termination
|RECORD=41|OwnerIndex=428|IndexInSheet=306|OwnerPartId=-1|Location.X=360|Location.Y=820|Color=8388608|FontID=1|IsHidden=T|Text=Thermoplastic|Name=Insulation Material
|RECORD=41|OwnerIndex=428|IndexInSheet=307|OwnerPartId=-1|Location.X=360|Location.Y=820|Color=8388608|FontID=1|IsHidden=T|Text=50V|Name=Max Voltage Rating (AC)
|RECORD=41|OwnerIndex=428|IndexInSheet=308|OwnerPartId=-1|Location.X=360|Location.Y=820|Color=8388608|FontID=1|IsHidden=T|Text=500mA|Name=Current Rating
|RECORD=34|OwnerIndex=428|IndexInSheet=-1|OwnerPartId=-1|Location.X=360|Location.Y=820|Color=8388608|FontID=1|Text=J44|Name=Designator|ReadOnlyState=1
|RECORD=41|OwnerIndex=428|IndexInSheet=-1|OwnerPartId=1|Location.X=360|Location.Y=110|Color=8388608|FontID=1|Text=2199119-3|Name=Comment
|RECORD=44|OwnerIndex=428
|RECORD=45|OwnerIndex=809|IndexInSheet=-1|UseComponentLibrary=T|ModelName=FP-2199119-3-MFG|ModelType=PCBLIB|DatafileCount=1|ModelDatafileEntity0=FP-2199119-3-MFG|ModelDatafileKind0=PCBLib|IsCurrent=T|DatalinksLocked=T|DatabaseDatalinksLocked=T
|RECORD=46|OwnerIndex=810
|RECORD=48|OwnerIndex=810
|RECORD=4|IndexInSheet=44|OwnerPartId=-1|Location.X=580|Location.Y=710|Color=8388608|FontID=1|Text=10MHz to module
|RECORD=28|IndexInSheet=45|OwnerPartId=-1|Location.X=580|Location.Y=660|Corner.X=649|Corner.X_Frac=25477|Corner.Y=672|Corner.Y_Frac=10|AreaColor=16777215|FontID=1|IsSolid=T|Alignment=1|WordWrap=T|ClipToRect=T|Text=1PPS to Module|TextMargin_Frac=5
|RECORD=1|LibReference=RES-2|ComponentDescription=Chip Resistor, 0 Ohm, 0.1 W, -55 to 155 degC, 0402 (1005 Metric), RoHS, Tape and Reel|PartCount=2|DisplayModeCount=1|IndexInSheet=46|OwnerPartId=-1|Location.X=200|Location.Y=550|CurrentPartId=1|LibraryPath=*|SourceLibraryName=Altium Content Vault|TargetFileName=*|AreaColor=11599871|Color=128|PartIDLocked=T|DesignItemId=CMP-2000-07451-1|AllPinCount=2|ComponentKindVersion2=5
|RECORD=2|OwnerIndex=815|OwnerPartId=1|FormalType=1|Electrical=4|PinConglomerate=32|PinLength=10|Location.X=220|Location.Y=550|Name=2|Designator=2|PinPropagationDelay=0.000000E+000
|RECORD=2|OwnerIndex=815|OwnerPartId=1|FormalType=1|Electrical=4|PinConglomerate=34|PinLength=10|Location.X=200|Location.Y=550|Name=1|Designator=1|PinPropagationDelay=0.000000E+000
|RECORD=6|OwnerIndex=815|IsNotAccesible=T|IndexInSheet=2|OwnerPartId=1|LineWidth=1|Color=16711680|LocationCount=10|X1=220|Y1=550|X2=216|Y2=550|X3=215|Y3=548|X4=213|Y4=552|X5=211|Y5=548|X6=209|Y6=552|X7=207|Y7=548|X8=205|Y8=552|X9=204|Y9=550|X10=200|Y10=550
|RECORD=41|OwnerIndex=815|IndexInSheet=3|OwnerPartId=-1|Location.X=188|Location.Y=565|Color=8388608|FontID=1|IsHidden=T|Text=50V|Name=Voltage Rating (DC)
|RECORD=41|OwnerIndex=815|IndexInSheet=4|OwnerPartId=-1|Location.X=188|Location.Y=565|Color=8388608|FontID=1|IsHidden=T|Text=2|Name=Number of Terminations
|RECORD=41|OwnerIndex=815|IndexInSheet=5|OwnerPartId=-1|Location.X=188|Location.Y=565|Color=8388608|FontID=1|IsHidden=T|Text=SurfaceMount|Name=Mount
|RECORD=41|OwnerIndex=815|IndexInSheet=6|OwnerPartId=-1|Location.X=188|Location.Y=565|Color=8388608|FontID=1|IsHidden=T|Text=0.35mm|Name=Height
|RECORD=41|OwnerIndex=815|IndexInSheet=7|OwnerPartId=-1|Location.X=188|Location.Y=565|Color=8388608|FontID=1|IsHidden=T|Text=TapeandReel|Name=Packaging
|RECORD=41|OwnerIndex=815|IndexInSheet=8|OwnerPartId=-1|Location.X=188|Location.Y=565|Color=8388608|FontID=1|IsHidden=T|Text=Tin|Name=Contact Plating
|RECORD=41|OwnerIndex=815|IndexInSheet=9|OwnerPartId=-1|Location.X=188|Location.Y=565|Color=8388608|FontID=3|IsHidden=T|Text=http://www.panasonic.com/|Name=Manufacturer URL
|RECORD=41|OwnerIndex=815|IndexInSheet=10|OwnerPartId=-1|Location.X=188|Location.Y=565|Color=8388608|FontID=1|IsHidden=T|Text=ThickFilm|Name=Composition
|RECORD=41|OwnerIndex=815|IndexInSheet=11|OwnerPartId=-1|Location.X=188|Location.Y=565|Color=8388608|FontID=1|IsHidden=T|Text=155degC|Name=Max Operating Temperature
|RECORD=41|OwnerIndex=815|IndexInSheet=12|OwnerPartId=-1|Location.X=188|Location.Y=565|Color=8388608|FontID=1|IsHidden=T|Text=600ppm/??C|Name=Temperature Coefficient
|RECORD=41|OwnerIndex=815|IndexInSheet=13|OwnerPartId=-1|Location.X=188|Location.Y=565|Color=8388608|FontID=1|IsHidden=T|Text=NoSVHC|Name=REACH SVHC
|RECORD=41|OwnerIndex=815|IndexInSheet=14|OwnerPartId=-1|Location.X=188|Location.Y=565|Color=8388608|FontID=1|IsHidden=T|Text=0402|Name=Case/Package
|RECORD=41|OwnerIndex=815|IndexInSheet=15|OwnerPartId=-1|Location.X=188|Location.Y=565|Color=8388608|FontID=1|IsHidden=T|Text=100mW|Name=Max Power Dissipation
|RECORD=41|OwnerIndex=815|IndexInSheet=16|OwnerPartId=-1|Location.X=188|Location.Y=565|Color=8388608|FontID=1|IsHidden=T|Text=402|Name=Package Reference
|RECORD=41|OwnerIndex=815|IndexInSheet=17|OwnerPartId=-1|Location.X=188|Location.Y=565|Color=8388608|FontID=1|IsHidden=T|Text=0.5mm|Name=Depth
|RECORD=41|OwnerIndex=815|IndexInSheet=18|OwnerPartId=-1|Location.X=188|Location.Y=565|Color=8388608|FontID=1|IsHidden=T|Text=Panasonic|Name=Manufacturer
|RECORD=41|OwnerIndex=815|IndexInSheet=19|OwnerPartId=-1|Location.X=188|Location.Y=565|Color=8388608|FontID=1|IsHidden=T|Text=2-Pin Surface Mount Device, Body 1 x 0.5 mm|Name=Package Description
|RECORD=41|OwnerIndex=815|IndexInSheet=20|OwnerPartId=-1|Location.X=188|Location.Y=565|Color=8388608|FontID=3|IsHidden=T|Text=https://industrial.panasonic.com/cdbs/www-data/pdf/RDA0000/AOA0000C301.pdf|Name=Datasheet URL
|RECORD=41|OwnerIndex=815|IndexInSheet=21|OwnerPartId=-1|Location.X=188|Location.Y=565|Color=8388608|FontID=1|IsHidden=T|Text=True|Name=RoHSCompliant
|RECORD=41|OwnerIndex=815|IndexInSheet=22|OwnerPartId=-1|Location.X=188|Location.Y=565|Color=8388608|FontID=1|IsHidden=T|Text=0402|Name=Case Code (Imperial)
|RECORD=41|OwnerIndex=815|IndexInSheet=23|OwnerPartId=-1|Location.X=188|Location.Y=565|Color=8388608|FontID=1|IsHidden=T|Text=0mOhm|Name=Resistance
|RECORD=41|OwnerIndex=815|IndexInSheet=24|OwnerPartId=-1|Location.X=188|Location.Y=565|Color=8388608|FontID=1|IsHidden=T|Text=Not|Name=Military Standard
|RECORD=41|OwnerIndex=815|IndexInSheet=25|OwnerPartId=-1|Location.X=188|Location.Y=565|Color=8388608|FontID=1|IsHidden=T|Text=5%|Name=Tolerance
|RECORD=41|OwnerIndex=815|IndexInSheet=26|OwnerPartId=-1|Location.X=188|Location.Y=565|Color=8388608|FontID=1|IsHidden=T|Text=-55degC|Name=Min Operating Temperature
|RECORD=41|OwnerIndex=815|IndexInSheet=27|OwnerPartId=-1|Location.X=188|Location.Y=565|Color=8388608|FontID=1|IsHidden=T|Text=100mW|Name=Power Rating
|RECORD=41|OwnerIndex=815|IndexInSheet=28|OwnerPartId=-1|Location.X=188|Location.Y=565|Color=8388608|FontID=1|IsHidden=T|Text=03/2015|Name=Datasheet Version
|RECORD=41|OwnerIndex=815|IndexInSheet=29|OwnerPartId=-1|Location.X=188|Location.Y=565|Color=8388608|FontID=1|IsHidden=T|Text=1mm|Name=Length
|RECORD=41|OwnerIndex=815|IndexInSheet=30|OwnerPartId=-1|Location.X=188|Location.Y=565|Color=8388608|FontID=1|IsHidden=T|Text=1005|Name=Case Code (Metric)
|RECORD=41|OwnerIndex=815|IndexInSheet=31|OwnerPartId=-1|Location.X=188|Location.Y=565|Color=8388608|FontID=1|IsHidden=T|Text=SMD/SMT|Name=Termination
|RECORD=41|OwnerIndex=815|IndexInSheet=32|OwnerPartId=-1|Location.X=188|Location.Y=565|Color=8388608|FontID=1|IsHidden=T|Text=SurfaceMount|Name=Mounting Technology
|RECORD=41|OwnerIndex=815|IndexInSheet=33|OwnerPartId=-1|Location.X=188|Location.Y=565|Color=8388608|FontID=1|IsHidden=T|Text=50V|Name=Voltage Rating
|RECORD=41|OwnerIndex=815|IndexInSheet=34|OwnerPartId=-1|Location.X=188|Location.Y=565|Color=8388608|FontID=1|IsHidden=T|Text=0.02inch|Name=Width
|RECORD=41|OwnerIndex=815|IndexInSheet=35|OwnerPartId=-1|Location.X=188|Location.Y=565|Color=8388608|FontID=1|IsHidden=T|Text=1|Name=Package Quantity
|RECORD=41|OwnerIndex=815|IndexInSheet=36|OwnerPartId=-1|Location.X=188|Location.Y=565|Color=8388608|FontID=1|IsHidden=T|Text=LeadFree|Name=Lead Free
|RECORD=41|OwnerIndex=815|IndexInSheet=37|OwnerPartId=-1|Location.X=188|Location.Y=565|Color=8388608|FontID=1|IsHidden=T|Text=No|Name=Radiation Hardening
|RECORD=34|OwnerIndex=815|IndexInSheet=-1|OwnerPartId=-1|Location.X=180|Location.Y=550|Color=8388608|FontID=1|Text=R130|Name=Designator|ReadOnlyState=1
|RECORD=41|OwnerIndex=815|IndexInSheet=-1|OwnerPartId=-1|Location.X=220|Location.Y=550|Color=8388608|FontID=1|Text=DNI_0_1%_0402|Name=Comment
|RECORD=44|OwnerIndex=815
|RECORD=45|OwnerIndex=858|IndexInSheet=-1|Description=Chip Resistor, 2-Leads, Body 1.05x0.55mm, IPC High Density|UseComponentLibrary=T|ModelName=RESC1005X40X25LL05T05|ModelType=PCBLIB|DatafileCount=1|ModelDatafileEntity0=RESC1005X40X25LL05T05|ModelDatafileKind0=PCBLib|IsCurrent=T|DatalinksLocked=T|DatabaseDatalinksLocked=T
|RECORD=46|OwnerIndex=859
|RECORD=48|OwnerIndex=859
|RECORD=41|OwnerIndex=861|IndexInSheet=-1|OwnerPartId=-1|Color=8388608|FontID=1|IsHidden=T|Text=2D|Name=Available Preview Images
|RECORD=45|OwnerIndex=858|IndexInSheet=-1|Description=Chip Resistor, 2-Leads, Body 1.05x0.55mm, IPC Low Density|UseComponentLibrary=T|ModelName=RESC1005X40X25ML05T05|ModelType=PCBLIB|DatafileCount=1|ModelDatafileEntity0=RESC1005X40X25ML05T05|ModelDatafileKind0=PCBLib|DatalinksLocked=T|DatabaseDatalinksLocked=T
|RECORD=46|OwnerIndex=863
|RECORD=48|OwnerIndex=863
|RECORD=41|OwnerIndex=865|IndexInSheet=-1|OwnerPartId=-1|Color=8388608|FontID=1|IsHidden=T|Text=2D|Name=Available Preview Images
|RECORD=45|OwnerIndex=858|IndexInSheet=-1|Description=Chip Resistor, 2-Leads, Body 1.05x0.55mm, IPC Medium Density|UseComponentLibrary=T|ModelName=RESC1005X40X25NL05T05|ModelType=PCBLIB|DatafileCount=1|ModelDatafileEntity0=RESC1005X40X25NL05T05|ModelDatafileKind0=PCBLib|DatalinksLocked=T|DatabaseDatalinksLocked=T
|RECORD=46|OwnerIndex=867
|RECORD=48|OwnerIndex=867
|RECORD=41|OwnerIndex=869|IndexInSheet=-1|OwnerPartId=-1|Color=8388608|FontID=1|IsHidden=T|Text=2D|Name=Available Preview Images
|RECORD=4|IndexInSheet=47|OwnerPartId=-1|Location.X=210|Location.Y=560|Color=8388608|FontID=1|Text=1PPS out here on some cards
|RECORD=1|LibReference=RES-2|ComponentDescription=Chip Resistor, 0 Ohm, 0.1 W, -55 to 155 degC, 0402 (1005 Metric), RoHS, Tape and Reel|PartCount=2|DisplayModeCount=1|IndexInSheet=48|OwnerPartId=-1|Location.X=490|Location.Y=440|CurrentPartId=1|LibraryPath=*|SourceLibraryName=Altium Content Vault|TargetFileName=*|AreaColor=11599871|Color=128|PartIDLocked=T|DesignItemId=CMP-2000-07451-1|AllPinCount=2
|RECORD=2|OwnerIndex=872|OwnerPartId=1|FormalType=1|Electrical=4|PinConglomerate=32|PinLength=10|Location.X=510|Location.Y=440|Name=2|Designator=2|PinPropagationDelay=0.000000E+000
|RECORD=2|OwnerIndex=872|OwnerPartId=1|FormalType=1|Electrical=4|PinConglomerate=34|PinLength=10|Location.X=490|Location.Y=440|Name=1|Designator=1|PinPropagationDelay=0.000000E+000
|RECORD=6|OwnerIndex=872|IsNotAccesible=T|IndexInSheet=2|OwnerPartId=1|LineWidth=1|Color=16711680|LocationCount=10|X1=510|Y1=440|X2=506|Y2=440|X3=505|Y3=438|X4=503|Y4=442|X5=501|Y5=438|X6=499|Y6=442|X7=497|Y7=438|X8=495|Y8=442|X9=494|Y9=440|X10=490|Y10=440
|RECORD=41|OwnerIndex=872|IndexInSheet=3|OwnerPartId=-1|Location.X=478|Location.Y=455|Color=8388608|FontID=1|IsHidden=T|Text=50V|Name=Voltage Rating (DC)
|RECORD=41|OwnerIndex=872|IndexInSheet=4|OwnerPartId=-1|Location.X=478|Location.Y=455|Color=8388608|FontID=1|IsHidden=T|Text=2|Name=Number of Terminations
|RECORD=41|OwnerIndex=872|IndexInSheet=5|OwnerPartId=-1|Location.X=478|Location.Y=455|Color=8388608|FontID=1|IsHidden=T|Text=SurfaceMount|Name=Mount
|RECORD=41|OwnerIndex=872|IndexInSheet=6|OwnerPartId=-1|Location.X=478|Location.Y=455|Color=8388608|FontID=1|IsHidden=T|Text=0.35mm|Name=Height
|RECORD=41|OwnerIndex=872|IndexInSheet=7|OwnerPartId=-1|Location.X=478|Location.Y=455|Color=8388608|FontID=1|IsHidden=T|Text=TapeandReel|Name=Packaging
|RECORD=41|OwnerIndex=872|IndexInSheet=8|OwnerPartId=-1|Location.X=478|Location.Y=455|Color=8388608|FontID=1|IsHidden=T|Text=Tin|Name=Contact Plating
|RECORD=41|OwnerIndex=872|IndexInSheet=9|OwnerPartId=-1|Location.X=478|Location.Y=455|Color=8388608|FontID=3|IsHidden=T|Text=http://www.panasonic.com/|Name=Manufacturer URL
|RECORD=41|OwnerIndex=872|IndexInSheet=10|OwnerPartId=-1|Location.X=478|Location.Y=455|Color=8388608|FontID=1|IsHidden=T|Text=ThickFilm|Name=Composition
|RECORD=41|OwnerIndex=872|IndexInSheet=11|OwnerPartId=-1|Location.X=478|Location.Y=455|Color=8388608|FontID=1|IsHidden=T|Text=155degC|Name=Max Operating Temperature
|RECORD=41|OwnerIndex=872|IndexInSheet=12|OwnerPartId=-1|Location.X=478|Location.Y=455|Color=8388608|FontID=1|IsHidden=T|Text=600ppm/??C|Name=Temperature Coefficient
|RECORD=41|OwnerIndex=872|IndexInSheet=13|OwnerPartId=-1|Location.X=478|Location.Y=455|Color=8388608|FontID=1|IsHidden=T|Text=NoSVHC|Name=REACH SVHC
|RECORD=41|OwnerIndex=872|IndexInSheet=14|OwnerPartId=-1|Location.X=478|Location.Y=455|Color=8388608|FontID=1|IsHidden=T|Text=0402|Name=Case/Package
|RECORD=41|OwnerIndex=872|IndexInSheet=15|OwnerPartId=-1|Location.X=478|Location.Y=455|Color=8388608|FontID=1|IsHidden=T|Text=100mW|Name=Max Power Dissipation
|RECORD=41|OwnerIndex=872|IndexInSheet=16|OwnerPartId=-1|Location.X=478|Location.Y=455|Color=8388608|FontID=1|IsHidden=T|Text=402|Name=Package Reference
|RECORD=41|OwnerIndex=872|IndexInSheet=17|OwnerPartId=-1|Location.X=478|Location.Y=455|Color=8388608|FontID=1|IsHidden=T|Text=0.5mm|Name=Depth
|RECORD=41|OwnerIndex=872|IndexInSheet=18|OwnerPartId=-1|Location.X=478|Location.Y=455|Color=8388608|FontID=1|IsHidden=T|Text=Panasonic|Name=Manufacturer
|RECORD=41|OwnerIndex=872|IndexInSheet=19|OwnerPartId=-1|Location.X=478|Location.Y=455|Color=8388608|FontID=1|IsHidden=T|Text=2-Pin Surface Mount Device, Body 1 x 0.5 mm|Name=Package Description
|RECORD=41|OwnerIndex=872|IndexInSheet=20|OwnerPartId=-1|Location.X=478|Location.Y=455|Color=8388608|FontID=3|IsHidden=T|Text=https://industrial.panasonic.com/cdbs/www-data/pdf/RDA0000/AOA0000C301.pdf|Name=Datasheet URL
|RECORD=41|OwnerIndex=872|IndexInSheet=21|OwnerPartId=-1|Location.X=478|Location.Y=455|Color=8388608|FontID=1|IsHidden=T|Text=True|Name=RoHSCompliant
|RECORD=41|OwnerIndex=872|IndexInSheet=22|OwnerPartId=-1|Location.X=478|Location.Y=455|Color=8388608|FontID=1|IsHidden=T|Text=0402|Name=Case Code (Imperial)
|RECORD=41|OwnerIndex=872|IndexInSheet=23|OwnerPartId=-1|Location.X=478|Location.Y=455|Color=8388608|FontID=1|IsHidden=T|Text=0mOhm|Name=Resistance
|RECORD=41|OwnerIndex=872|IndexInSheet=24|OwnerPartId=-1|Location.X=478|Location.Y=455|Color=8388608|FontID=1|IsHidden=T|Text=Not|Name=Military Standard
|RECORD=41|OwnerIndex=872|IndexInSheet=25|OwnerPartId=-1|Location.X=478|Location.Y=455|Color=8388608|FontID=1|IsHidden=T|Text=5%|Name=Tolerance
|RECORD=41|OwnerIndex=872|IndexInSheet=26|OwnerPartId=-1|Location.X=478|Location.Y=455|Color=8388608|FontID=1|IsHidden=T|Text=-55degC|Name=Min Operating Temperature
|RECORD=41|OwnerIndex=872|IndexInSheet=27|OwnerPartId=-1|Location.X=478|Location.Y=455|Color=8388608|FontID=1|IsHidden=T|Text=100mW|Name=Power Rating
|RECORD=41|OwnerIndex=872|IndexInSheet=28|OwnerPartId=-1|Location.X=478|Location.Y=455|Color=8388608|FontID=1|IsHidden=T|Text=03/2015|Name=Datasheet Version
|RECORD=41|OwnerIndex=872|IndexInSheet=29|OwnerPartId=-1|Location.X=478|Location.Y=455|Color=8388608|FontID=1|IsHidden=T|Text=1mm|Name=Length
|RECORD=41|OwnerIndex=872|IndexInSheet=30|OwnerPartId=-1|Location.X=478|Location.Y=455|Color=8388608|FontID=1|IsHidden=T|Text=1005|Name=Case Code (Metric)
|RECORD=41|OwnerIndex=872|IndexInSheet=31|OwnerPartId=-1|Location.X=478|Location.Y=455|Color=8388608|FontID=1|IsHidden=T|Text=SMD/SMT|Name=Termination
|RECORD=41|OwnerIndex=872|IndexInSheet=32|OwnerPartId=-1|Location.X=478|Location.Y=455|Color=8388608|FontID=1|IsHidden=T|Text=SurfaceMount|Name=Mounting Technology
|RECORD=41|OwnerIndex=872|IndexInSheet=33|OwnerPartId=-1|Location.X=478|Location.Y=455|Color=8388608|FontID=1|IsHidden=T|Text=50V|Name=Voltage Rating
|RECORD=41|OwnerIndex=872|IndexInSheet=34|OwnerPartId=-1|Location.X=478|Location.Y=455|Color=8388608|FontID=1|IsHidden=T|Text=0.02inch|Name=Width
|RECORD=41|OwnerIndex=872|IndexInSheet=35|OwnerPartId=-1|Location.X=478|Location.Y=455|Color=8388608|FontID=1|IsHidden=T|Text=1|Name=Package Quantity
|RECORD=41|OwnerIndex=872|IndexInSheet=36|OwnerPartId=-1|Location.X=478|Location.Y=455|Color=8388608|FontID=1|IsHidden=T|Text=LeadFree|Name=Lead Free
|RECORD=41|OwnerIndex=872|IndexInSheet=37|OwnerPartId=-1|Location.X=478|Location.Y=455|Color=8388608|FontID=1|IsHidden=T|Text=No|Name=Radiation Hardening
|RECORD=34|OwnerIndex=872|IndexInSheet=-1|OwnerPartId=-1|Location.X=470|Location.Y=440|Color=8388608|FontID=1|Text=R138|Name=Designator|ReadOnlyState=1
|RECORD=41|OwnerIndex=872|IndexInSheet=-1|OwnerPartId=-1|Location.X=510|Location.Y=440|Color=8388608|FontID=1|Text=0_1%_0402|Name=Comment
|RECORD=44|OwnerIndex=872
|RECORD=45|OwnerIndex=915|IndexInSheet=-1|Description=Chip Resistor, 2-Leads, Body 1.05x0.55mm, IPC High Density|UseComponentLibrary=T|ModelName=RESC1005X40X25LL05T05|ModelType=PCBLIB|DatafileCount=1|ModelDatafileEntity0=RESC1005X40X25LL05T05|ModelDatafileKind0=PCBLib|IsCurrent=T|DatalinksLocked=T|DatabaseDatalinksLocked=T
|RECORD=46|OwnerIndex=916
|RECORD=48|OwnerIndex=916
|RECORD=41|OwnerIndex=918|IndexInSheet=-1|OwnerPartId=-1|Color=8388608|FontID=1|IsHidden=T|Text=2D|Name=Available Preview Images
|RECORD=45|OwnerIndex=915|IndexInSheet=-1|Description=Chip Resistor, 2-Leads, Body 1.05x0.55mm, IPC Low Density|UseComponentLibrary=T|ModelName=RESC1005X40X25ML05T05|ModelType=PCBLIB|DatafileCount=1|ModelDatafileEntity0=RESC1005X40X25ML05T05|ModelDatafileKind0=PCBLib|DatalinksLocked=T|DatabaseDatalinksLocked=T
|RECORD=46|OwnerIndex=920
|RECORD=48|OwnerIndex=920
|RECORD=41|OwnerIndex=922|IndexInSheet=-1|OwnerPartId=-1|Color=8388608|FontID=1|IsHidden=T|Text=2D|Name=Available Preview Images
|RECORD=45|OwnerIndex=915|IndexInSheet=-1|Description=Chip Resistor, 2-Leads, Body 1.05x0.55mm, IPC Medium Density|UseComponentLibrary=T|ModelName=RESC1005X40X25NL05T05|ModelType=PCBLIB|DatafileCount=1|ModelDatafileEntity0=RESC1005X40X25NL05T05|ModelDatafileKind0=PCBLib|DatalinksLocked=T|DatabaseDatalinksLocked=T
|RECORD=46|OwnerIndex=924
|RECORD=48|OwnerIndex=924
|RECORD=41|OwnerIndex=926|IndexInSheet=-1|OwnerPartId=-1|Color=8388608|FontID=1|IsHidden=T|Text=2D|Name=Available Preview Images
|RECORD=17|IndexInSheet=49|OwnerPartId=-1|ShowNetName=T|Location.X=570|Location.Y=440|Color=255|FontID=1|Text=M2_GPS1_TP1|IsCrossSheetConnector=T
|RECORD=27|IndexInSheet=50|OwnerPartId=-1|LineWidth=1|Color=8388608|LocationCount=2|X1=140|Y1=770|X2=160|Y2=770
|RECORD=27|IndexInSheet=51|OwnerPartId=-1|LineWidth=1|Color=8388608|LocationCount=2|X1=140|Y1=710|X2=160|Y2=710
|RECORD=27|IndexInSheet=52|OwnerPartId=-1|LineWidth=1|Color=8388608|LocationCount=2|X1=140|Y1=630|X2=160|Y2=630
|RECORD=27|IndexInSheet=53|OwnerPartId=-1|LineWidth=1|Color=8388608|LocationCount=2|X1=140|Y1=570|X2=160|Y2=570
|RECORD=27|IndexInSheet=54|OwnerPartId=-1|LineWidth=1|Color=8388608|LocationCount=2|X1=140|Y1=510|X2=160|Y2=510
|RECORD=27|IndexInSheet=55|OwnerPartId=-1|LineWidth=1|Color=8388608|LocationCount=2|X1=140|Y1=450|X2=160|Y2=450
|RECORD=27|IndexInSheet=56|OwnerPartId=-1|LineWidth=1|Color=8388608|LocationCount=2|X1=140|Y1=390|X2=160|Y2=390
|RECORD=27|IndexInSheet=57|OwnerPartId=-1|LineWidth=1|Color=8388608|LocationCount=2|X1=140|Y1=330|X2=160|Y2=330
|RECORD=27|IndexInSheet=58|OwnerPartId=-1|LineWidth=1|Color=8388608|LocationCount=2|X1=140|Y1=190|X2=160|Y2=190
|RECORD=27|IndexInSheet=59|OwnerPartId=-1|LineWidth=1|Color=8388608|LocationCount=2|X1=140|Y1=170|X2=160|Y2=170
|RECORD=27|IndexInSheet=60|OwnerPartId=-1|LineWidth=1|Color=8388608|LocationCount=3|X1=460|Y1=820|X2=460|Y2=800|X3=430|Y3=800
|RECORD=27|IndexInSheet=61|OwnerPartId=-1|LineWidth=1|Color=8388608|LocationCount=3|X1=430|Y1=780|X2=460|Y2=780|X3=460|Y3=800
|RECORD=27|IndexInSheet=62|OwnerPartId=-1|LineWidth=1|Color=8388608|LocationCount=3|X1=430|Y1=180|X2=460|Y2=180|X3=460|Y3=200
|RECORD=27|IndexInSheet=63|OwnerPartId=-1|LineWidth=1|Color=8388608|LocationCount=3|X1=430|Y1=160|X2=460|Y2=160|X3=460|Y3=180
|RECORD=27|IndexInSheet=64|OwnerPartId=-1|LineWidth=1|Color=8388608|LocationCount=4|X1=430|Y1=140|X2=460|Y2=140|X3=460|Y3=130|X4=460|Y4=120
|RECORD=27|IndexInSheet=65|OwnerPartId=-1|LineWidth=1|Color=8388608|LocationCount=2|X1=140|Y1=130|X2=160|Y2=130
|RECORD=27|IndexInSheet=66|OwnerPartId=-1|LineWidth=1|Color=8388608|LocationCount=2|X1=140|Y1=550|X2=190|Y2=550
|RECORD=27|IndexInSheet=67|OwnerPartId=-1|LineWidth=1|Color=8388608|LocationCount=2|X1=230|Y1=550|X2=290|Y2=550
|RECORD=27|IndexInSheet=68|OwnerPartId=-1|LineWidth=1|Color=8388608|LocationCount=2|X1=430|Y1=440|X2=480|Y2=440
|RECORD=27|IndexInSheet=69|OwnerPartId=-1|LineWidth=1|Color=8388608|LocationCount=2|X1=520|Y1=440|X2=570|Y2=440
|RECORD=27|IndexInSheet=70|OwnerPartId=-1|LineWidth=1|Color=8388608|LocationCount=2|X1=430|Y1=400|X2=510|Y2=400
|RECORD=27|IndexInSheet=71|OwnerPartId=-1|LineWidth=1|Color=8388608|LocationCount=2|X1=140|Y1=230|X2=200|Y2=230
|RECORD=27|IndexInSheet=72|OwnerPartId=-1|LineWidth=1|Color=8388608|LocationCount=2|X1=430|Y1=280|X2=510|Y2=280
|RECORD=27|IndexInSheet=73|OwnerPartId=-1|LineWidth=1|Color=8388608|LocationCount=2|X1=430|Y1=260|X2=510|Y2=260
|RECORD=27|IndexInSheet=74|OwnerPartId=-1|LineWidth=1|Color=8388608|LocationCount=2|X1=430|Y1=420|X2=570|Y2=420
|RECORD=4|IndexInSheet=75|OwnerPartId=-1|Location.X=600|Location.Y=480|Color=8388608|FontID=1|Text=I2C & IRQ
|RECORD=1|LibReference=RES|PartCount=2|DisplayModeCount=2|IndexInSheet=76|OwnerPartId=-1|Location.X=470|Location.Y=520|Orientation=1|CurrentPartId=1|SourceLibraryName=Altium Content Vault|TargetFileName=*|AreaColor=11599871|Color=128|PartIDLocked=F|DesignItemId=CMP-2002-05217-1|AllPinCount=2
|RECORD=2|OwnerIndex=955|OwnerPartId=1|OwnerPartDisplayMode=1|FormalType=1|Electrical=4|PinConglomerate=33|PinLength=10|Location.X=480|Location.Y=540|Name=2|Designator=2|PinPropagationDelay=0.000000E+000
|RECORD=2|OwnerIndex=955|OwnerPartId=1|OwnerPartDisplayMode=1|FormalType=1|Electrical=4|PinConglomerate=35|PinLength=10|Location.X=480|Location.Y=520|Name=1|Designator=1|PinPropagationDelay=0.000000E+000
|RECORD=14|OwnerIndex=955|IsNotAccesible=T|IndexInSheet=2|OwnerPartId=1|OwnerPartDisplayMode=1|Location.X=476|Location.Y=520|Corner.X=484|Corner.Y=540|LineWidth=1|Color=16711680|AreaColor=11599871
|RECORD=2|OwnerIndex=955|OwnerPartId=1|FormalType=1|Electrical=4|PinConglomerate=33|PinLength=10|Location.X=480|Location.Y=540|Name=2|Designator=2|PinPropagationDelay=0.000000E+000
|RECORD=2|OwnerIndex=955|OwnerPartId=1|FormalType=1|Electrical=4|PinConglomerate=35|PinLength=10|Location.X=480|Location.Y=520|Name=1|Designator=1|PinPropagationDelay=0.000000E+000
|RECORD=6|OwnerIndex=955|IsNotAccesible=T|IndexInSheet=5|OwnerPartId=1|LineWidth=1|Color=16711680|LocationCount=10|X1=480|Y1=540|X2=480|Y2=536|X3=482|Y3=535|X4=478|Y4=533|X5=482|Y5=531|X6=478|Y6=529|X7=482|Y7=527|X8=478|Y8=525|X9=480|Y9=524|X10=480|Y10=520
|RECORD=41|OwnerIndex=955|IndexInSheet=6|OwnerPartId=-1|Location.X=477|Location.Y=552|Color=8388608|FontID=1|IsHidden=T|Text=Bourns|Name=Manufacturer
|RECORD=41|OwnerIndex=955|IndexInSheet=7|OwnerPartId=-1|Location.X=477|Location.Y=552|Color=8388608|FontID=1|IsHidden=T|Text=CR0402-FX-4701GLF|Name=Part Number
|RECORD=34|OwnerIndex=955|IndexInSheet=-1|OwnerPartId=-1|Location.X=480|Location.Y=510|Orientation=1|Color=8388608|FontID=2|Text=R132|Name=Designator|ReadOnlyState=1
|RECORD=41|OwnerIndex=955|IndexInSheet=-1|OwnerPartId=-1|Location.X=490|Location.Y=510|Orientation=1|Color=8388608|FontID=2|Text=4.7K_1%_0402|Name=Comment
|RECORD=44|OwnerIndex=955
|RECORD=45|OwnerIndex=970|IndexInSheet=-1|Description=Chip Resistor, 2-Leads, Body 1.00x0.50mm, IPC Medium Density|UseComponentLibrary=T|ModelName=RESC1005X40X25NL10T10|ModelType=PCBLIB|DatafileCount=1|ModelDatafileEntity0=RESC1005X40X25NL10T10|ModelDatafileKind0=PCBLib|IsCurrent=T|DatalinksLocked=T|DatabaseDatalinksLocked=T
|RECORD=46|OwnerIndex=971
|RECORD=48|OwnerIndex=971
|RECORD=41|OwnerIndex=973|IndexInSheet=-1|OwnerPartId=-1|Color=8388608|FontID=1|IsHidden=T|Text=2D|Name=Available Preview Images
|RECORD=45|OwnerIndex=970|IndexInSheet=-1|Description=Chip Resistor, 2-Leads, Body 1.00x0.50mm, IPC High Density|UseComponentLibrary=T|ModelName=RESC1005X40X25LL10T10|ModelType=PCBLIB|DatafileCount=1|ModelDatafileEntity0=RESC1005X40X25LL10T10|ModelDatafileKind0=PCBLib|DatalinksLocked=T|DatabaseDatalinksLocked=T
|RECORD=46|OwnerIndex=975
|RECORD=48|OwnerIndex=975
|RECORD=41|OwnerIndex=977|IndexInSheet=-1|OwnerPartId=-1|Color=8388608|FontID=1|IsHidden=T|Text=2D|Name=Available Preview Images
|RECORD=45|OwnerIndex=970|IndexInSheet=-1|Description=Chip Resistor, 2-Leads, Body 1.00x0.50mm, IPC Low Density|UseComponentLibrary=T|ModelName=RESC1005X40X25ML10T10|ModelType=PCBLIB|DatafileCount=1|ModelDatafileEntity0=RESC1005X40X25ML10T10|ModelDatafileKind0=PCBLib|DatalinksLocked=T|DatabaseDatalinksLocked=T
|RECORD=46|OwnerIndex=979
|RECORD=48|OwnerIndex=979
|RECORD=41|OwnerIndex=981|IndexInSheet=-1|OwnerPartId=-1|Color=8388608|FontID=1|IsHidden=T|Text=2D|Name=Available Preview Images
|RECORD=1|LibReference=RES|PartCount=2|DisplayModeCount=2|IndexInSheet=77|OwnerPartId=-1|Location.X=490|Location.Y=520|Orientation=1|CurrentPartId=1|SourceLibraryName=Altium Content Vault|TargetFileName=*|AreaColor=11599871|Color=128|PartIDLocked=F|DesignItemId=CMP-2002-05217-1|AllPinCount=2
|RECORD=2|OwnerIndex=983|OwnerPartId=1|OwnerPartDisplayMode=1|FormalType=1|Electrical=4|PinConglomerate=33|PinLength=10|Location.X=500|Location.Y=540|Name=2|Designator=2|PinPropagationDelay=0.000000E+000
|RECORD=2|OwnerIndex=983|OwnerPartId=1|OwnerPartDisplayMode=1|FormalType=1|Electrical=4|PinConglomerate=35|PinLength=10|Location.X=500|Location.Y=520|Name=1|Designator=1|PinPropagationDelay=0.000000E+000
|RECORD=14|OwnerIndex=983|IsNotAccesible=T|IndexInSheet=2|OwnerPartId=1|OwnerPartDisplayMode=1|Location.X=496|Location.Y=520|Corner.X=504|Corner.Y=540|LineWidth=1|Color=16711680|AreaColor=11599871
|RECORD=2|OwnerIndex=983|OwnerPartId=1|FormalType=1|Electrical=4|PinConglomerate=33|PinLength=10|Location.X=500|Location.Y=540|Name=2|Designator=2|PinPropagationDelay=0.000000E+000
|RECORD=2|OwnerIndex=983|OwnerPartId=1|FormalType=1|Electrical=4|PinConglomerate=35|PinLength=10|Location.X=500|Location.Y=520|Name=1|Designator=1|PinPropagationDelay=0.000000E+000
|RECORD=6|OwnerIndex=983|IsNotAccesible=T|IndexInSheet=5|OwnerPartId=1|LineWidth=1|Color=16711680|LocationCount=10|X1=500|Y1=540|X2=500|Y2=536|X3=502|Y3=535|X4=498|Y4=533|X5=502|Y5=531|X6=498|Y6=529|X7=502|Y7=527|X8=498|Y8=525|X9=500|Y9=524|X10=500|Y10=520
|RECORD=41|OwnerIndex=983|IndexInSheet=6|OwnerPartId=-1|Location.X=497|Location.Y=552|Color=8388608|FontID=1|IsHidden=T|Text=Bourns|Name=Manufacturer
|RECORD=41|OwnerIndex=983|IndexInSheet=7|OwnerPartId=-1|Location.X=497|Location.Y=552|Color=8388608|FontID=1|IsHidden=T|Text=CR0402-FX-4701GLF|Name=Part Number
|RECORD=34|OwnerIndex=983|IndexInSheet=-1|OwnerPartId=-1|Location.X=500|Location.Y=510|Orientation=1|Color=8388608|FontID=2|Text=R133|Name=Designator|ReadOnlyState=1
|RECORD=41|OwnerIndex=983|IndexInSheet=-1|OwnerPartId=-1|Location.X=510|Location.Y=510|Orientation=1|Color=8388608|FontID=2|Text=4.7K_1%_0402|Name=Comment
|RECORD=44|OwnerIndex=983
|RECORD=45|OwnerIndex=998|IndexInSheet=-1|Description=Chip Resistor, 2-Leads, Body 1.00x0.50mm, IPC Medium Density|UseComponentLibrary=T|ModelName=RESC1005X40X25NL10T10|ModelType=PCBLIB|DatafileCount=1|ModelDatafileEntity0=RESC1005X40X25NL10T10|ModelDatafileKind0=PCBLib|IsCurrent=T|DatalinksLocked=T|DatabaseDatalinksLocked=T
|RECORD=46|OwnerIndex=999
|RECORD=48|OwnerIndex=999
|RECORD=41|OwnerIndex=1001|IndexInSheet=-1|OwnerPartId=-1|Color=8388608|FontID=1|IsHidden=T|Text=2D|Name=Available Preview Images
|RECORD=45|OwnerIndex=998|IndexInSheet=-1|Description=Chip Resistor, 2-Leads, Body 1.00x0.50mm, IPC High Density|UseComponentLibrary=T|ModelName=RESC1005X40X25LL10T10|ModelType=PCBLIB|DatafileCount=1|ModelDatafileEntity0=RESC1005X40X25LL10T10|ModelDatafileKind0=PCBLib|DatalinksLocked=T|DatabaseDatalinksLocked=T
|RECORD=46|OwnerIndex=1003
|RECORD=48|OwnerIndex=1003
|RECORD=41|OwnerIndex=1005|IndexInSheet=-1|OwnerPartId=-1|Color=8388608|FontID=1|IsHidden=T|Text=2D|Name=Available Preview Images
|RECORD=45|OwnerIndex=998|IndexInSheet=-1|Description=Chip Resistor, 2-Leads, Body 1.00x0.50mm, IPC Low Density|UseComponentLibrary=T|ModelName=RESC1005X40X25ML10T10|ModelType=PCBLIB|DatafileCount=1|ModelDatafileEntity0=RESC1005X40X25ML10T10|ModelDatafileKind0=PCBLib|DatalinksLocked=T|DatabaseDatalinksLocked=T
|RECORD=46|OwnerIndex=1007
|RECORD=48|OwnerIndex=1007
|RECORD=41|OwnerIndex=1009|IndexInSheet=-1|OwnerPartId=-1|Color=8388608|FontID=1|IsHidden=T|Text=2D|Name=Available Preview Images
|RECORD=1|LibReference=RES|PartCount=2|DisplayModeCount=2|IndexInSheet=78|OwnerPartId=-1|Location.X=510|Location.Y=520|Orientation=1|CurrentPartId=1|SourceLibraryName=Altium Content Vault|TargetFileName=*|AreaColor=11599871|Color=128|PartIDLocked=F|DesignItemId=CMP-2002-05217-1|AllPinCount=2
|RECORD=2|OwnerIndex=1011|OwnerPartId=1|OwnerPartDisplayMode=1|FormalType=1|Electrical=4|PinConglomerate=33|PinLength=10|Location.X=520|Location.Y=540|Name=2|Designator=2|PinPropagationDelay=0.000000E+000
|RECORD=2|OwnerIndex=1011|OwnerPartId=1|OwnerPartDisplayMode=1|FormalType=1|Electrical=4|PinConglomerate=35|PinLength=10|Location.X=520|Location.Y=520|Name=1|Designator=1|PinPropagationDelay=0.000000E+000
|RECORD=14|OwnerIndex=1011|IsNotAccesible=T|IndexInSheet=2|OwnerPartId=1|OwnerPartDisplayMode=1|Location.X=516|Location.Y=520|Corner.X=524|Corner.Y=540|LineWidth=1|Color=16711680|AreaColor=11599871
|RECORD=2|OwnerIndex=1011|OwnerPartId=1|FormalType=1|Electrical=4|PinConglomerate=33|PinLength=10|Location.X=520|Location.Y=540|Name=2|Designator=2|PinPropagationDelay=0.000000E+000
|RECORD=2|OwnerIndex=1011|OwnerPartId=1|FormalType=1|Electrical=4|PinConglomerate=35|PinLength=10|Location.X=520|Location.Y=520|Name=1|Designator=1|PinPropagationDelay=0.000000E+000
|RECORD=6|OwnerIndex=1011|IsNotAccesible=T|IndexInSheet=5|OwnerPartId=1|LineWidth=1|Color=16711680|LocationCount=10|X1=520|Y1=540|X2=520|Y2=536|X3=522|Y3=535|X4=518|Y4=533|X5=522|Y5=531|X6=518|Y6=529|X7=522|Y7=527|X8=518|Y8=525|X9=520|Y9=524|X10=520|Y10=520
|RECORD=41|OwnerIndex=1011|IndexInSheet=6|OwnerPartId=-1|Location.X=517|Location.Y=552|Color=8388608|FontID=1|IsHidden=T|Text=Bourns|Name=Manufacturer
|RECORD=41|OwnerIndex=1011|IndexInSheet=7|OwnerPartId=-1|Location.X=517|Location.Y=552|Color=8388608|FontID=1|IsHidden=T|Text=CR0402-FX-4701GLF|Name=Part Number
|RECORD=34|OwnerIndex=1011|IndexInSheet=-1|OwnerPartId=-1|Location.X=520|Location.Y=510|Orientation=1|Color=8388608|FontID=2|Text=R134|Name=Designator|ReadOnlyState=1
|RECORD=41|OwnerIndex=1011|IndexInSheet=-1|OwnerPartId=-1|Location.X=530|Location.Y=510|Orientation=1|Color=8388608|FontID=2|Text=4.7K_1%_0402|Name=Comment
|RECORD=44|OwnerIndex=1011
|RECORD=45|OwnerIndex=1026|IndexInSheet=-1|Description=Chip Resistor, 2-Leads, Body 1.00x0.50mm, IPC Medium Density|UseComponentLibrary=T|ModelName=RESC1005X40X25NL10T10|ModelType=PCBLIB|DatafileCount=1|ModelDatafileEntity0=RESC1005X40X25NL10T10|ModelDatafileKind0=PCBLib|IsCurrent=T|DatalinksLocked=T|DatabaseDatalinksLocked=T
|RECORD=46|OwnerIndex=1027
|RECORD=48|OwnerIndex=1027
|RECORD=41|OwnerIndex=1029|IndexInSheet=-1|OwnerPartId=-1|Color=8388608|FontID=1|IsHidden=T|Text=2D|Name=Available Preview Images
|RECORD=45|OwnerIndex=1026|IndexInSheet=-1|Description=Chip Resistor, 2-Leads, Body 1.00x0.50mm, IPC High Density|UseComponentLibrary=T|ModelName=RESC1005X40X25LL10T10|ModelType=PCBLIB|DatafileCount=1|ModelDatafileEntity0=RESC1005X40X25LL10T10|ModelDatafileKind0=PCBLib|DatalinksLocked=T|DatabaseDatalinksLocked=T
|RECORD=46|OwnerIndex=1031
|RECORD=48|OwnerIndex=1031
|RECORD=41|OwnerIndex=1033|IndexInSheet=-1|OwnerPartId=-1|Color=8388608|FontID=1|IsHidden=T|Text=2D|Name=Available Preview Images
|RECORD=45|OwnerIndex=1026|IndexInSheet=-1|Description=Chip Resistor, 2-Leads, Body 1.00x0.50mm, IPC Low Density|UseComponentLibrary=T|ModelName=RESC1005X40X25ML10T10|ModelType=PCBLIB|DatafileCount=1|ModelDatafileEntity0=RESC1005X40X25ML10T10|ModelDatafileKind0=PCBLib|DatalinksLocked=T|DatabaseDatalinksLocked=T
|RECORD=46|OwnerIndex=1035
|RECORD=48|OwnerIndex=1035
|RECORD=41|OwnerIndex=1037|IndexInSheet=-1|OwnerPartId=-1|Color=8388608|FontID=1|IsHidden=T|Text=2D|Name=Available Preview Images
|RECORD=27|IndexInSheet=79|OwnerPartId=-1|LineWidth=1|Color=8388608|LocationCount=3|X1=480|Y1=550|X2=480|Y2=570|X3=460|Y3=570
|RECORD=27|IndexInSheet=80|OwnerPartId=-1|LineWidth=1|Color=8388608|LocationCount=3|X1=480|Y1=570|X2=500|Y2=570|X3=500|Y3=550
|RECORD=27|IndexInSheet=81|OwnerPartId=-1|LineWidth=1|Color=8388608|LocationCount=3|X1=500|Y1=570|X2=520|Y2=570|X3=520|Y3=550
|RECORD=27|IndexInSheet=82|OwnerPartId=-1|LineWidth=1|Color=8388608|LocationCount=2|X1=520|Y1=510|X2=520|Y2=460
|RECORD=27|IndexInSheet=83|OwnerPartId=-1|LineWidth=1|Color=8388608|LocationCount=2|X1=500|Y1=510|X2=500|Y2=480
|RECORD=27|IndexInSheet=84|OwnerPartId=-1|LineWidth=1|Color=8388608|LocationCount=2|X1=480|Y1=510|X2=480|Y2=500
|RECORD=27|IndexInSheet=85|OwnerPartId=-1|LineWidth=1|Color=8388608|LocationCount=14|X1=160|Y1=110|X2=160|Y2=130|X3=160|Y3=170|X4=160|Y4=190|X5=160|Y5=330|X6=160|Y6=390|X7=160|Y7=450|X8=160|Y8=510|X9=160|Y9=570|X10=160|Y10=630|X11=160|Y11=710|X12=160|Y12=770|X13=160|Y13=790|X14=140|Y14=790
|RECORD=27|IndexInSheet=86|OwnerPartId=-1|LineWidth=1|Color=8388608|LocationCount=4|X1=460|Y1=780|X2=460|Y2=570|X3=460|Y3=200|X4=430|Y4=200
|RECORD=27|IndexInSheet=87|OwnerPartId=-1|LineWidth=1|Color=8388608|LocationCount=3|X1=430|Y1=460|X2=520|Y2=460|X3=530|Y3=460
|RECORD=27|IndexInSheet=88|OwnerPartId=-1|LineWidth=1|Color=8388608|LocationCount=3|X1=430|Y1=480|X2=500|Y2=480|X3=530|Y3=480
|RECORD=27|IndexInSheet=89|OwnerPartId=-1|LineWidth=1|Color=8388608|LocationCount=3|X1=430|Y1=500|X2=480|Y2=500|X3=530|Y3=500
|RECORD=17|IndexInSheet=90|OwnerPartId=-1|Style=4|ShowNetName=T|Location.X=790|Location.Y=100|Orientation=3|Color=128|FontID=1|Text=GND
|RECORD=17|IndexInSheet=91|OwnerPartId=-1|Style=4|ShowNetName=T|Location.X=1090|Location.Y=110|Orientation=3|Color=128|FontID=1|Text=GND
|RECORD=17|IndexInSheet=92|OwnerPartId=-1|ShowNetName=T|Location.X=1140|Location.Y=390|Color=255|FontID=1|Text=GPS2_RST|IsCrossSheetConnector=T
|RECORD=17|IndexInSheet=93|OwnerPartId=-1|ShowNetName=T|Location.X=1140|Location.Y=410|Color=255|FontID=1|Text=M2_GPS2_TP2|IsCrossSheetConnector=T
|RECORD=17|IndexInSheet=94|OwnerPartId=-1|ShowNetName=T|Location.X=910|Location.Y=540|Color=255|FontID=1|Text=M2_GPS2_TP1|IsCrossSheetConnector=T
|RECORD=17|IndexInSheet=95|OwnerPartId=-1|ShowNetName=T|Location.X=1140|Location.Y=270|Color=255|FontID=1|Text=M2_GPS2_RX|IsCrossSheetConnector=T
|RECORD=17|IndexInSheet=96|OwnerPartId=-1|ShowNetName=T|Location.X=1140|Location.Y=250|Color=255|FontID=1|Text=M2_GPS2_TX|IsCrossSheetConnector=T
|RECORD=17|IndexInSheet=97|OwnerPartId=-1|ShowNetName=T|Location.X=830|Location.Y=220|Color=255|FontID=1|Text=GPS2_RST|IsCrossSheetConnector=T
|RECORD=17|IndexInSheet=98|OwnerPartId=-1|ShowNetName=T|Location.X=1160|Location.Y=490|Color=255|FontID=1|Text=GPS2_PIN13|IsCrossSheetConnector=T
|RECORD=17|IndexInSheet=99|OwnerPartId=-1|ShowNetName=T|Location.X=1160|Location.Y=470|Color=255|FontID=1|Text=GPS2_PIN14|IsCrossSheetConnector=T
|RECORD=17|IndexInSheet=100|OwnerPartId=-1|ShowNetName=T|Location.X=1160|Location.Y=450|Color=255|FontID=1|Text=GPS2_PIN15|IsCrossSheetConnector=T
|RECORD=17|IndexInSheet=101|OwnerPartId=-1|ShowNetName=T|Location.X=1120|Location.Y=690|Color=255|FontID=1|Text=M2_GPS2_PIN11|IsCrossSheetConnector=T
|RECORD=17|IndexInSheet=102|OwnerPartId=-1|ShowNetName=T|Location.X=1120|Location.Y=670|Color=255|FontID=1|Text=M2_GPS2_PIN12|IsCrossSheetConnector=T
|RECORD=1|LibReference=a14843ccfa78e5d0b739856168502fb|ComponentDescription=CONN M.2 FEMALE 67POS 0.020 GOLD|PartCount=3|DisplayModeCount=1|IndexInSheet=103|OwnerPartId=-1|Location.X=770|Location.Y=800|CurrentPartId=1|LibraryPath=*|SourceLibraryName=Altium Content Vault|TargetFileName=*|AreaColor=11599871|Color=128|PartIDLocked=T|DesignItemId=CMP-03365-000004-1|AllPinCount=69
|RECORD=14|OwnerIndex=1063|IsNotAccesible=T|OwnerPartId=1|Location.X=700|Location.Y=100|Corner.X=750|Corner.Y=820|LineWidth=1|Color=128|AreaColor=11599871|IsSolid=T
|RECORD=8|OwnerIndex=1063|IsNotAccesible=T|IndexInSheet=1|OwnerPartId=1|Location.X=725|Location.Y=800|Radius=3|SecondaryRadius=3|LineWidth=1|Color=16711680
|RECORD=13|OwnerIndex=1063|IsNotAccesible=T|IndexInSheet=2|OwnerPartId=1|Location.X=728|Location.Y=800|Corner.X=750|Corner.Y=800|LineWidth=1|Color=16711680
|RECORD=8|OwnerIndex=1063|IsNotAccesible=T|IndexInSheet=3|OwnerPartId=1|Location.X=725|Location.Y=780|Radius=3|SecondaryRadius=3|LineWidth=1|Color=16711680
|RECORD=13|OwnerIndex=1063|IsNotAccesible=T|IndexInSheet=4|OwnerPartId=1|Location.X=728|Location.Y=780|Corner.X=750|Corner.Y=780|LineWidth=1|Color=16711680
|RECORD=8|OwnerIndex=1063|IsNotAccesible=T|IndexInSheet=5|OwnerPartId=1|Location.X=725|Location.Y=760|Radius=3|SecondaryRadius=3|LineWidth=1|Color=16711680
|RECORD=13|OwnerIndex=1063|IsNotAccesible=T|IndexInSheet=6|OwnerPartId=1|Location.X=728|Location.Y=760|Corner.X=750|Corner.Y=760|LineWidth=1|Color=16711680
|RECORD=8|OwnerIndex=1063|IsNotAccesible=T|IndexInSheet=7|OwnerPartId=1|Location.X=725|Location.Y=740|Radius=3|SecondaryRadius=3|LineWidth=1|Color=16711680
|RECORD=13|OwnerIndex=1063|IsNotAccesible=T|IndexInSheet=8|OwnerPartId=1|Location.X=728|Location.Y=740|Corner.X=750|Corner.Y=740|LineWidth=1|Color=16711680
|RECORD=8|OwnerIndex=1063|IsNotAccesible=T|IndexInSheet=9|OwnerPartId=1|Location.X=725|Location.Y=720|Radius=3|SecondaryRadius=3|LineWidth=1|Color=16711680
|RECORD=13|OwnerIndex=1063|IsNotAccesible=T|IndexInSheet=10|OwnerPartId=1|Location.X=728|Location.Y=720|Corner.X=750|Corner.Y=720|LineWidth=1|Color=16711680
|RECORD=8|OwnerIndex=1063|IsNotAccesible=T|IndexInSheet=11|OwnerPartId=1|Location.X=725|Location.Y=700|Radius=3|SecondaryRadius=3|LineWidth=1|Color=16711680
|RECORD=13|OwnerIndex=1063|IsNotAccesible=T|IndexInSheet=12|OwnerPartId=1|Location.X=728|Location.Y=700|Corner.X=750|Corner.Y=700|LineWidth=1|Color=16711680
|RECORD=8|OwnerIndex=1063|IsNotAccesible=T|IndexInSheet=13|OwnerPartId=1|Location.X=725|Location.Y=680|Radius=3|SecondaryRadius=3|LineWidth=1|Color=16711680
|RECORD=13|OwnerIndex=1063|IsNotAccesible=T|IndexInSheet=14|OwnerPartId=1|Location.X=728|Location.Y=680|Corner.X=750|Corner.Y=680|LineWidth=1|Color=16711680
|RECORD=8|OwnerIndex=1063|IsNotAccesible=T|IndexInSheet=15|OwnerPartId=1|Location.X=725|Location.Y=660|Radius=3|SecondaryRadius=3|LineWidth=1|Color=16711680
|RECORD=13|OwnerIndex=1063|IsNotAccesible=T|IndexInSheet=16|OwnerPartId=1|Location.X=728|Location.Y=660|Corner.X=750|Corner.Y=660|LineWidth=1|Color=16711680
|RECORD=8|OwnerIndex=1063|IsNotAccesible=T|IndexInSheet=17|OwnerPartId=1|Location.X=725|Location.Y=640|Radius=3|SecondaryRadius=3|LineWidth=1|Color=16711680
|RECORD=13|OwnerIndex=1063|IsNotAccesible=T|IndexInSheet=18|OwnerPartId=1|Location.X=728|Location.Y=640|Corner.X=750|Corner.Y=640|LineWidth=1|Color=16711680
|RECORD=8|OwnerIndex=1063|IsNotAccesible=T|IndexInSheet=19|OwnerPartId=1|Location.X=725|Location.Y=620|Radius=3|SecondaryRadius=3|LineWidth=1|Color=16711680
|RECORD=13|OwnerIndex=1063|IsNotAccesible=T|IndexInSheet=20|OwnerPartId=1|Location.X=728|Location.Y=620|Corner.X=750|Corner.Y=620|LineWidth=1|Color=16711680
|RECORD=8|OwnerIndex=1063|IsNotAccesible=T|IndexInSheet=21|OwnerPartId=1|Location.X=725|Location.Y=600|Radius=3|SecondaryRadius=3|LineWidth=1|Color=16711680
|RECORD=13|OwnerIndex=1063|IsNotAccesible=T|IndexInSheet=22|OwnerPartId=1|Location.X=728|Location.Y=600|Corner.X=750|Corner.Y=600|LineWidth=1|Color=16711680
|RECORD=8|OwnerIndex=1063|IsNotAccesible=T|IndexInSheet=23|OwnerPartId=1|Location.X=725|Location.Y=580|Radius=3|SecondaryRadius=3|LineWidth=1|Color=16711680
|RECORD=13|OwnerIndex=1063|IsNotAccesible=T|IndexInSheet=24|OwnerPartId=1|Location.X=728|Location.Y=580|Corner.X=750|Corner.Y=580|LineWidth=1|Color=16711680
|RECORD=8|OwnerIndex=1063|IsNotAccesible=T|IndexInSheet=25|OwnerPartId=1|Location.X=725|Location.Y=560|Radius=3|SecondaryRadius=3|LineWidth=1|Color=16711680
|RECORD=13|OwnerIndex=1063|IsNotAccesible=T|IndexInSheet=26|OwnerPartId=1|Location.X=728|Location.Y=560|Corner.X=750|Corner.Y=560|LineWidth=1|Color=16711680
|RECORD=8|OwnerIndex=1063|IsNotAccesible=T|IndexInSheet=27|OwnerPartId=1|Location.X=725|Location.Y=540|Radius=3|SecondaryRadius=3|LineWidth=1|Color=16711680
|RECORD=13|OwnerIndex=1063|IsNotAccesible=T|IndexInSheet=28|OwnerPartId=1|Location.X=728|Location.Y=540|Corner.X=750|Corner.Y=540|LineWidth=1|Color=16711680
|RECORD=8|OwnerIndex=1063|IsNotAccesible=T|IndexInSheet=29|OwnerPartId=1|Location.X=725|Location.Y=520|Radius=3|SecondaryRadius=3|LineWidth=1|Color=16711680
|RECORD=13|OwnerIndex=1063|IsNotAccesible=T|IndexInSheet=30|OwnerPartId=1|Location.X=728|Location.Y=520|Corner.X=750|Corner.Y=520|LineWidth=1|Color=16711680
|RECORD=8|OwnerIndex=1063|IsNotAccesible=T|IndexInSheet=31|OwnerPartId=1|Location.X=725|Location.Y=500|Radius=3|SecondaryRadius=3|LineWidth=1|Color=16711680
|RECORD=13|OwnerIndex=1063|IsNotAccesible=T|IndexInSheet=32|OwnerPartId=1|Location.X=728|Location.Y=500|Corner.X=750|Corner.Y=500|LineWidth=1|Color=16711680
|RECORD=8|OwnerIndex=1063|IsNotAccesible=T|IndexInSheet=33|OwnerPartId=1|Location.X=725|Location.Y=480|Radius=3|SecondaryRadius=3|LineWidth=1|Color=16711680
|RECORD=13|OwnerIndex=1063|IsNotAccesible=T|IndexInSheet=34|OwnerPartId=1|Location.X=728|Location.Y=480|Corner.X=750|Corner.Y=480|LineWidth=1|Color=16711680
|RECORD=8|OwnerIndex=1063|IsNotAccesible=T|IndexInSheet=35|OwnerPartId=1|Location.X=725|Location.Y=460|Radius=3|SecondaryRadius=3|LineWidth=1|Color=16711680
|RECORD=13|OwnerIndex=1063|IsNotAccesible=T|IndexInSheet=36|OwnerPartId=1|Location.X=728|Location.Y=460|Corner.X=750|Corner.Y=460|LineWidth=1|Color=16711680
|RECORD=8|OwnerIndex=1063|IsNotAccesible=T|IndexInSheet=37|OwnerPartId=1|Location.X=725|Location.Y=440|Radius=3|SecondaryRadius=3|LineWidth=1|Color=16711680
|RECORD=13|OwnerIndex=1063|IsNotAccesible=T|IndexInSheet=38|OwnerPartId=1|Location.X=728|Location.Y=440|Corner.X=750|Corner.Y=440|LineWidth=1|Color=16711680
|RECORD=8|OwnerIndex=1063|IsNotAccesible=T|IndexInSheet=39|OwnerPartId=1|Location.X=725|Location.Y=420|Radius=3|SecondaryRadius=3|LineWidth=1|Color=16711680
|RECORD=13|OwnerIndex=1063|IsNotAccesible=T|IndexInSheet=40|OwnerPartId=1|Location.X=728|Location.Y=420|Corner.X=750|Corner.Y=420|LineWidth=1|Color=16711680
|RECORD=8|OwnerIndex=1063|IsNotAccesible=T|IndexInSheet=41|OwnerPartId=1|Location.X=725|Location.Y=400|Radius=3|SecondaryRadius=3|LineWidth=1|Color=16711680
|RECORD=13|OwnerIndex=1063|IsNotAccesible=T|IndexInSheet=42|OwnerPartId=1|Location.X=728|Location.Y=400|Corner.X=750|Corner.Y=400|LineWidth=1|Color=16711680
|RECORD=8|OwnerIndex=1063|IsNotAccesible=T|IndexInSheet=43|OwnerPartId=1|Location.X=725|Location.Y=380|Radius=3|SecondaryRadius=3|LineWidth=1|Color=16711680
|RECORD=13|OwnerIndex=1063|IsNotAccesible=T|IndexInSheet=44|OwnerPartId=1|Location.X=728|Location.Y=380|Corner.X=750|Corner.Y=380|LineWidth=1|Color=16711680
|RECORD=8|OwnerIndex=1063|IsNotAccesible=T|IndexInSheet=45|OwnerPartId=1|Location.X=725|Location.Y=360|Radius=3|SecondaryRadius=3|LineWidth=1|Color=16711680
|RECORD=13|OwnerIndex=1063|IsNotAccesible=T|IndexInSheet=46|OwnerPartId=1|Location.X=728|Location.Y=360|Corner.X=750|Corner.Y=360|LineWidth=1|Color=16711680
|RECORD=8|OwnerIndex=1063|IsNotAccesible=T|IndexInSheet=47|OwnerPartId=1|Location.X=725|Location.Y=340|Radius=3|SecondaryRadius=3|LineWidth=1|Color=16711680
|RECORD=13|OwnerIndex=1063|IsNotAccesible=T|IndexInSheet=48|OwnerPartId=1|Location.X=728|Location.Y=340|Corner.X=750|Corner.Y=340|LineWidth=1|Color=16711680
|RECORD=8|OwnerIndex=1063|IsNotAccesible=T|IndexInSheet=49|OwnerPartId=1|Location.X=725|Location.Y=320|Radius=3|SecondaryRadius=3|LineWidth=1|Color=16711680
|RECORD=13|OwnerIndex=1063|IsNotAccesible=T|IndexInSheet=50|OwnerPartId=1|Location.X=728|Location.Y=320|Corner.X=750|Corner.Y=320|LineWidth=1|Color=16711680
|RECORD=8|OwnerIndex=1063|IsNotAccesible=T|IndexInSheet=51|OwnerPartId=1|Location.X=725|Location.Y=300|Radius=3|SecondaryRadius=3|LineWidth=1|Color=16711680
|RECORD=13|OwnerIndex=1063|IsNotAccesible=T|IndexInSheet=52|OwnerPartId=1|Location.X=728|Location.Y=300|Corner.X=750|Corner.Y=300|LineWidth=1|Color=16711680
|RECORD=8|OwnerIndex=1063|IsNotAccesible=T|IndexInSheet=53|OwnerPartId=1|Location.X=725|Location.Y=280|Radius=3|SecondaryRadius=3|LineWidth=1|Color=16711680
|RECORD=13|OwnerIndex=1063|IsNotAccesible=T|IndexInSheet=54|OwnerPartId=1|Location.X=728|Location.Y=280|Corner.X=750|Corner.Y=280|LineWidth=1|Color=16711680
|RECORD=8|OwnerIndex=1063|IsNotAccesible=T|IndexInSheet=55|OwnerPartId=1|Location.X=725|Location.Y=260|Radius=3|SecondaryRadius=3|LineWidth=1|Color=16711680
|RECORD=13|OwnerIndex=1063|IsNotAccesible=T|IndexInSheet=56|OwnerPartId=1|Location.X=728|Location.Y=260|Corner.X=750|Corner.Y=260|LineWidth=1|Color=16711680
|RECORD=8|OwnerIndex=1063|IsNotAccesible=T|IndexInSheet=57|OwnerPartId=1|Location.X=725|Location.Y=240|Radius=3|SecondaryRadius=3|LineWidth=1|Color=16711680
|RECORD=13|OwnerIndex=1063|IsNotAccesible=T|IndexInSheet=58|OwnerPartId=1|Location.X=728|Location.Y=240|Corner.X=750|Corner.Y=240|LineWidth=1|Color=16711680
|RECORD=8|OwnerIndex=1063|IsNotAccesible=T|IndexInSheet=59|OwnerPartId=1|Location.X=725|Location.Y=220|Radius=3|SecondaryRadius=3|LineWidth=1|Color=16711680
|RECORD=13|OwnerIndex=1063|IsNotAccesible=T|IndexInSheet=60|OwnerPartId=1|Location.X=728|Location.Y=220|Corner.X=750|Corner.Y=220|LineWidth=1|Color=16711680
|RECORD=8|OwnerIndex=1063|IsNotAccesible=T|IndexInSheet=61|OwnerPartId=1|Location.X=725|Location.Y=200|Radius=3|SecondaryRadius=3|LineWidth=1|Color=16711680
|RECORD=13|OwnerIndex=1063|IsNotAccesible=T|IndexInSheet=62|OwnerPartId=1|Location.X=728|Location.Y=200|Corner.X=750|Corner.Y=200|LineWidth=1|Color=16711680
|RECORD=8|OwnerIndex=1063|IsNotAccesible=T|IndexInSheet=63|OwnerPartId=1|Location.X=725|Location.Y=180|Radius=3|SecondaryRadius=3|LineWidth=1|Color=16711680
|RECORD=13|OwnerIndex=1063|IsNotAccesible=T|IndexInSheet=64|OwnerPartId=1|Location.X=728|Location.Y=180|Corner.X=750|Corner.Y=180|LineWidth=1|Color=16711680
|RECORD=8|OwnerIndex=1063|IsNotAccesible=T|IndexInSheet=65|OwnerPartId=1|Location.X=725|Location.Y=160|Radius=3|SecondaryRadius=3|LineWidth=1|Color=16711680
|RECORD=13|OwnerIndex=1063|IsNotAccesible=T|IndexInSheet=66|OwnerPartId=1|Location.X=728|Location.Y=160|Corner.X=750|Corner.Y=160|LineWidth=1|Color=16711680
|RECORD=8|OwnerIndex=1063|IsNotAccesible=T|IndexInSheet=67|OwnerPartId=1|Location.X=725|Location.Y=140|Radius=3|SecondaryRadius=3|LineWidth=1|Color=16711680
|RECORD=13|OwnerIndex=1063|IsNotAccesible=T|IndexInSheet=68|OwnerPartId=1|Location.X=728|Location.Y=140|Corner.X=750|Corner.Y=140|LineWidth=1|Color=16711680
|RECORD=8|OwnerIndex=1063|IsNotAccesible=T|IndexInSheet=69|OwnerPartId=1|Location.X=725|Location.Y=120|Radius=3|SecondaryRadius=3|LineWidth=1|Color=16711680
|RECORD=13|OwnerIndex=1063|IsNotAccesible=T|IndexInSheet=70|OwnerPartId=1|Location.X=728|Location.Y=120|Corner.X=750|Corner.Y=120|LineWidth=1|Color=16711680
|RECORD=4|OwnerIndex=1063|IsNotAccesible=T|IndexInSheet=71|OwnerPartId=1|Location.X=743|Location.Y=812|Justification=8|Color=8388608|FontID=1|Text=1
|RECORD=4|OwnerIndex=1063|IsNotAccesible=T|IndexInSheet=72|OwnerPartId=1|Location.X=743|Location.Y=792|Justification=8|Color=8388608|FontID=1|Text=3
|RECORD=4|OwnerIndex=1063|IsNotAccesible=T|IndexInSheet=73|OwnerPartId=1|Location.X=743|Location.Y=772|Justification=8|Color=8388608|FontID=1|Text=5
|RECORD=4|OwnerIndex=1063|IsNotAccesible=T|IndexInSheet=74|OwnerPartId=1|Location.X=743|Location.Y=752|Justification=8|Color=8388608|FontID=1|Text=7
|RECORD=4|OwnerIndex=1063|IsNotAccesible=T|IndexInSheet=75|OwnerPartId=1|Location.X=743|Location.Y=732|Justification=8|Color=8388608|FontID=1|Text=9
|RECORD=4|OwnerIndex=1063|IsNotAccesible=T|IndexInSheet=76|OwnerPartId=1|Location.X=743|Location.Y=712|Justification=8|Color=8388608|FontID=1|Text=11
|RECORD=4|OwnerIndex=1063|IsNotAccesible=T|IndexInSheet=77|OwnerPartId=1|Location.X=743|Location.Y=692|Justification=8|Color=8388608|FontID=1|Text=21
|RECORD=4|OwnerIndex=1063|IsNotAccesible=T|IndexInSheet=78|OwnerPartId=1|Location.X=743|Location.Y=672|Justification=8|Color=8388608|FontID=1|Text=23
|RECORD=4|OwnerIndex=1063|IsNotAccesible=T|IndexInSheet=79|OwnerPartId=1|Location.X=743|Location.Y=652|Justification=8|Color=8388608|FontID=1|Text=25
|RECORD=4|OwnerIndex=1063|IsNotAccesible=T|IndexInSheet=80|OwnerPartId=1|Location.X=743|Location.Y=632|Justification=8|Color=8388608|FontID=1|Text=27
|RECORD=4|OwnerIndex=1063|IsNotAccesible=T|IndexInSheet=81|OwnerPartId=1|Location.X=743|Location.Y=612|Justification=8|Color=8388608|FontID=1|Text=29
|RECORD=4|OwnerIndex=1063|IsNotAccesible=T|IndexInSheet=82|OwnerPartId=1|Location.X=743|Location.Y=592|Justification=8|Color=8388608|FontID=1|Text=31
|RECORD=4|OwnerIndex=1063|IsNotAccesible=T|IndexInSheet=83|OwnerPartId=1|Location.X=743|Location.Y=572|Justification=8|Color=8388608|FontID=1|Text=33
|RECORD=4|OwnerIndex=1063|IsNotAccesible=T|IndexInSheet=84|OwnerPartId=1|Location.X=743|Location.Y=552|Justification=8|Color=8388608|FontID=1|Text=35
|RECORD=4|OwnerIndex=1063|IsNotAccesible=T|IndexInSheet=85|OwnerPartId=1|Location.X=743|Location.Y=532|Justification=8|Color=8388608|FontID=1|Text=37
|RECORD=4|OwnerIndex=1063|IsNotAccesible=T|IndexInSheet=86|OwnerPartId=1|Location.X=743|Location.Y=512|Justification=8|Color=8388608|FontID=1|Text=39
|RECORD=4|OwnerIndex=1063|IsNotAccesible=T|IndexInSheet=87|OwnerPartId=1|Location.X=743|Location.Y=492|Justification=8|Color=8388608|FontID=1|Text=41
|RECORD=4|OwnerIndex=1063|IsNotAccesible=T|IndexInSheet=88|OwnerPartId=1|Location.X=743|Location.Y=472|Justification=8|Color=8388608|FontID=1|Text=43
|RECORD=4|OwnerIndex=1063|IsNotAccesible=T|IndexInSheet=89|OwnerPartId=1|Location.X=743|Location.Y=452|Justification=8|Color=8388608|FontID=1|Text=45
|RECORD=4|OwnerIndex=1063|IsNotAccesible=T|IndexInSheet=90|OwnerPartId=1|Location.X=743|Location.Y=432|Justification=8|Color=8388608|FontID=1|Text=47
|RECORD=4|OwnerIndex=1063|IsNotAccesible=T|IndexInSheet=91|OwnerPartId=1|Location.X=743|Location.Y=412|Justification=8|Color=8388608|FontID=1|Text=49
|RECORD=4|OwnerIndex=1063|IsNotAccesible=T|IndexInSheet=92|OwnerPartId=1|Location.X=743|Location.Y=392|Justification=8|Color=8388608|FontID=1|Text=51
|RECORD=4|OwnerIndex=1063|IsNotAccesible=T|IndexInSheet=93|OwnerPartId=1|Location.X=743|Location.Y=372|Justification=8|Color=8388608|FontID=1|Text=53
|RECORD=4|OwnerIndex=1063|IsNotAccesible=T|IndexInSheet=94|OwnerPartId=1|Location.X=743|Location.Y=352|Justification=8|Color=8388608|FontID=1|Text=55
|RECORD=4|OwnerIndex=1063|IsNotAccesible=T|IndexInSheet=95|OwnerPartId=1|Location.X=743|Location.Y=332|Justification=8|Color=8388608|FontID=1|Text=57
|RECORD=4|OwnerIndex=1063|IsNotAccesible=T|IndexInSheet=96|OwnerPartId=1|Location.X=743|Location.Y=312|Justification=8|Color=8388608|FontID=1|Text=59
|RECORD=4|OwnerIndex=1063|IsNotAccesible=T|IndexInSheet=97|OwnerPartId=1|Location.X=743|Location.Y=292|Justification=8|Color=8388608|FontID=1|Text=61
|RECORD=4|OwnerIndex=1063|IsNotAccesible=T|IndexInSheet=98|OwnerPartId=1|Location.X=743|Location.Y=272|Justification=8|Color=8388608|FontID=1|Text=63
|RECORD=4|OwnerIndex=1063|IsNotAccesible=T|IndexInSheet=99|OwnerPartId=1|Location.X=743|Location.Y=252|Justification=8|Color=8388608|FontID=1|Text=65
|RECORD=4|OwnerIndex=1063|IsNotAccesible=T|IndexInSheet=100|OwnerPartId=1|Location.X=743|Location.Y=232|Justification=8|Color=8388608|FontID=1|Text=67
|RECORD=4|OwnerIndex=1063|IsNotAccesible=T|IndexInSheet=101|OwnerPartId=1|Location.X=743|Location.Y=212|Justification=8|Color=8388608|FontID=1|Text=69
|RECORD=4|OwnerIndex=1063|IsNotAccesible=T|IndexInSheet=102|OwnerPartId=1|Location.X=743|Location.Y=192|Justification=8|Color=8388608|FontID=1|Text=71
|RECORD=4|OwnerIndex=1063|IsNotAccesible=T|IndexInSheet=103|OwnerPartId=1|Location.X=743|Location.Y=172|Justification=8|Color=8388608|FontID=1|Text=73
|RECORD=4|OwnerIndex=1063|IsNotAccesible=T|IndexInSheet=104|OwnerPartId=1|Location.X=743|Location.Y=152|Justification=8|Color=8388608|FontID=1|Text=75
|RECORD=4|OwnerIndex=1063|IsNotAccesible=T|IndexInSheet=105|OwnerPartId=1|Location.X=743|Location.Y=132|Justification=8|Color=8388608|FontID=1|Text=MNT 2
|RECORD=2|OwnerIndex=1063|OwnerPartId=1|Electrical=4|PinConglomerate=48|PinLength=20|Location.X=750|Location.Y=800|Name=1|Designator=1|PinName_PositionConglomerate=16|Name_CustomFontID=1|PinDesignator_PositionConglomerate=16|Designator_CustomFontID=1|PinPropagationDelay=0.000000E+000
|RECORD=2|OwnerIndex=1063|OwnerPartId=1|Electrical=4|PinConglomerate=48|PinLength=20|Location.X=750|Location.Y=780|Name=3|Designator=3|PinName_PositionConglomerate=16|Name_CustomFontID=1|PinDesignator_PositionConglomerate=16|Designator_CustomFontID=1|PinPropagationDelay=0.000000E+000
|RECORD=2|OwnerIndex=1063|OwnerPartId=1|Electrical=4|PinConglomerate=48|PinLength=20|Location.X=750|Location.Y=760|Name=5|Designator=5|PinName_PositionConglomerate=16|Name_CustomFontID=1|PinDesignator_PositionConglomerate=16|Designator_CustomFontID=1|PinPropagationDelay=0.000000E+000
|RECORD=2|OwnerIndex=1063|OwnerPartId=1|Electrical=4|PinConglomerate=48|PinLength=20|Location.X=750|Location.Y=740|Name=7|Designator=7|PinName_PositionConglomerate=16|Name_CustomFontID=1|PinDesignator_PositionConglomerate=16|Designator_CustomFontID=1|PinPropagationDelay=0.000000E+000
|RECORD=2|OwnerIndex=1063|OwnerPartId=1|Electrical=4|PinConglomerate=48|PinLength=20|Location.X=750|Location.Y=720|Name=9|Designator=9|PinName_PositionConglomerate=16|Name_CustomFontID=1|PinDesignator_PositionConglomerate=16|Designator_CustomFontID=1|PinPropagationDelay=0.000000E+000
|RECORD=2|OwnerIndex=1063|OwnerPartId=1|Electrical=4|PinConglomerate=48|PinLength=20|Location.X=750|Location.Y=700|Name=11|Designator=11|PinName_PositionConglomerate=16|Name_CustomFontID=1|PinDesignator_PositionConglomerate=16|Designator_CustomFontID=1|PinPropagationDelay=0.000000E+000
|RECORD=2|OwnerIndex=1063|OwnerPartId=1|Electrical=4|PinConglomerate=48|PinLength=20|Location.X=750|Location.Y=680|Name=21|Designator=21|PinName_PositionConglomerate=16|Name_CustomFontID=1|PinDesignator_PositionConglomerate=16|Designator_CustomFontID=1|PinPropagationDelay=0.000000E+000
|RECORD=2|OwnerIndex=1063|OwnerPartId=1|Electrical=4|PinConglomerate=48|PinLength=20|Location.X=750|Location.Y=660|Name=23|Designator=23|PinName_PositionConglomerate=16|Name_CustomFontID=1|PinDesignator_PositionConglomerate=16|Designator_CustomFontID=1|PinPropagationDelay=0.000000E+000
|RECORD=2|OwnerIndex=1063|OwnerPartId=1|Electrical=4|PinConglomerate=48|PinLength=20|Location.X=750|Location.Y=640|Name=25|Designator=25|PinName_PositionConglomerate=16|Name_CustomFontID=1|PinDesignator_PositionConglomerate=16|Designator_CustomFontID=1|PinPropagationDelay=0.000000E+000
|RECORD=2|OwnerIndex=1063|OwnerPartId=1|Electrical=4|PinConglomerate=48|PinLength=20|Location.X=750|Location.Y=620|Name=27|Designator=27|PinName_PositionConglomerate=16|Name_CustomFontID=1|PinDesignator_PositionConglomerate=16|Designator_CustomFontID=1|PinPropagationDelay=0.000000E+000
|RECORD=2|OwnerIndex=1063|OwnerPartId=1|Electrical=4|PinConglomerate=48|PinLength=20|Location.X=750|Location.Y=600|Name=29|Designator=29|PinName_PositionConglomerate=16|Name_CustomFontID=1|PinDesignator_PositionConglomerate=16|Designator_CustomFontID=1|PinPropagationDelay=0.000000E+000
|RECORD=2|OwnerIndex=1063|OwnerPartId=1|Electrical=4|PinConglomerate=48|PinLength=20|Location.X=750|Location.Y=580|Name=31|Designator=31|PinName_PositionConglomerate=16|Name_CustomFontID=1|PinDesignator_PositionConglomerate=16|Designator_CustomFontID=1|PinPropagationDelay=0.000000E+000
|RECORD=2|OwnerIndex=1063|OwnerPartId=1|Electrical=4|PinConglomerate=48|PinLength=20|Location.X=750|Location.Y=560|Name=33|Designator=33|PinName_PositionConglomerate=16|Name_CustomFontID=1|PinDesignator_PositionConglomerate=16|Designator_CustomFontID=1|PinPropagationDelay=0.000000E+000
|RECORD=2|OwnerIndex=1063|OwnerPartId=1|Electrical=4|PinConglomerate=48|PinLength=20|Location.X=750|Location.Y=540|Name=35|Designator=35|PinName_PositionConglomerate=16|Name_CustomFontID=1|PinDesignator_PositionConglomerate=16|Designator_CustomFontID=1|PinPropagationDelay=0.000000E+000
|RECORD=2|OwnerIndex=1063|OwnerPartId=1|Electrical=4|PinConglomerate=48|PinLength=20|Location.X=750|Location.Y=520|Name=37|Designator=37|PinName_PositionConglomerate=16|Name_CustomFontID=1|PinDesignator_PositionConglomerate=16|Designator_CustomFontID=1|PinPropagationDelay=0.000000E+000
|RECORD=2|OwnerIndex=1063|OwnerPartId=1|Electrical=4|PinConglomerate=48|PinLength=20|Location.X=750|Location.Y=500|Name=39|Designator=39|PinName_PositionConglomerate=16|Name_CustomFontID=1|PinDesignator_PositionConglomerate=16|Designator_CustomFontID=1|PinPropagationDelay=0.000000E+000
|RECORD=2|OwnerIndex=1063|OwnerPartId=1|Electrical=4|PinConglomerate=48|PinLength=20|Location.X=750|Location.Y=480|Name=41|Designator=41|PinName_PositionConglomerate=16|Name_CustomFontID=1|PinDesignator_PositionConglomerate=16|Designator_CustomFontID=1|PinPropagationDelay=0.000000E+000
|RECORD=2|OwnerIndex=1063|OwnerPartId=1|Electrical=4|PinConglomerate=48|PinLength=20|Location.X=750|Location.Y=460|Name=43|Designator=43|PinName_PositionConglomerate=16|Name_CustomFontID=1|PinDesignator_PositionConglomerate=16|Designator_CustomFontID=1|PinPropagationDelay=0.000000E+000
|RECORD=2|OwnerIndex=1063|OwnerPartId=1|Electrical=4|PinConglomerate=48|PinLength=20|Location.X=750|Location.Y=440|Name=45|Designator=45|PinName_PositionConglomerate=16|Name_CustomFontID=1|PinDesignator_PositionConglomerate=16|Designator_CustomFontID=1|PinPropagationDelay=0.000000E+000
|RECORD=2|OwnerIndex=1063|OwnerPartId=1|Electrical=4|PinConglomerate=48|PinLength=20|Location.X=750|Location.Y=420|Name=47|Designator=47|PinName_PositionConglomerate=16|Name_CustomFontID=1|PinDesignator_PositionConglomerate=16|Designator_CustomFontID=1|PinPropagationDelay=0.000000E+000
|RECORD=2|OwnerIndex=1063|OwnerPartId=1|Electrical=4|PinConglomerate=48|PinLength=20|Location.X=750|Location.Y=400|Name=49|Designator=49|PinName_PositionConglomerate=16|Name_CustomFontID=1|PinDesignator_PositionConglomerate=16|Designator_CustomFontID=1|PinPropagationDelay=0.000000E+000
|RECORD=2|OwnerIndex=1063|OwnerPartId=1|Electrical=4|PinConglomerate=48|PinLength=20|Location.X=750|Location.Y=380|Name=51|Designator=51|PinName_PositionConglomerate=16|Name_CustomFontID=1|PinDesignator_PositionConglomerate=16|Designator_CustomFontID=1|PinPropagationDelay=0.000000E+000
|RECORD=2|OwnerIndex=1063|OwnerPartId=1|Electrical=4|PinConglomerate=48|PinLength=20|Location.X=750|Location.Y=360|Name=53|Designator=53|PinName_PositionConglomerate=16|Name_CustomFontID=1|PinDesignator_PositionConglomerate=16|Designator_CustomFontID=1|PinPropagationDelay=0.000000E+000
|RECORD=2|OwnerIndex=1063|OwnerPartId=1|Electrical=4|PinConglomerate=48|PinLength=20|Location.X=750|Location.Y=340|Name=55|Designator=55|PinName_PositionConglomerate=16|Name_CustomFontID=1|PinDesignator_PositionConglomerate=16|Designator_CustomFontID=1|PinPropagationDelay=0.000000E+000
|RECORD=2|OwnerIndex=1063|OwnerPartId=1|Electrical=4|PinConglomerate=48|PinLength=20|Location.X=750|Location.Y=320|Name=57|Designator=57|PinName_PositionConglomerate=16|Name_CustomFontID=1|PinDesignator_PositionConglomerate=16|Designator_CustomFontID=1|PinPropagationDelay=0.000000E+000
|RECORD=2|OwnerIndex=1063|OwnerPartId=1|Electrical=4|PinConglomerate=48|PinLength=20|Location.X=750|Location.Y=300|Name=59|Designator=59|PinName_PositionConglomerate=16|Name_CustomFontID=1|PinDesignator_PositionConglomerate=16|Designator_CustomFontID=1|PinPropagationDelay=0.000000E+000
|RECORD=2|OwnerIndex=1063|OwnerPartId=1|Electrical=4|PinConglomerate=48|PinLength=20|Location.X=750|Location.Y=280|Name=61|Designator=61|PinName_PositionConglomerate=16|Name_CustomFontID=1|PinDesignator_PositionConglomerate=16|Designator_CustomFontID=1|PinPropagationDelay=0.000000E+000
|RECORD=2|OwnerIndex=1063|OwnerPartId=1|Electrical=4|PinConglomerate=48|PinLength=20|Location.X=750|Location.Y=260|Name=63|Designator=63|PinName_PositionConglomerate=16|Name_CustomFontID=1|PinDesignator_PositionConglomerate=16|Designator_CustomFontID=1|PinPropagationDelay=0.000000E+000
|RECORD=2|OwnerIndex=1063|OwnerPartId=1|Electrical=4|PinConglomerate=48|PinLength=20|Location.X=750|Location.Y=240|Name=65|Designator=65|PinName_PositionConglomerate=16|Name_CustomFontID=1|PinDesignator_PositionConglomerate=16|Designator_CustomFontID=1|PinPropagationDelay=0.000000E+000
|RECORD=2|OwnerIndex=1063|OwnerPartId=1|Electrical=4|PinConglomerate=48|PinLength=20|Location.X=750|Location.Y=220|Name=67|Designator=67|PinName_PositionConglomerate=16|Name_CustomFontID=1|PinDesignator_PositionConglomerate=16|Designator_CustomFontID=1|PinPropagationDelay=0.000000E+000
|RECORD=2|OwnerIndex=1063|OwnerPartId=1|Electrical=4|PinConglomerate=48|PinLength=20|Location.X=750|Location.Y=200|Name=69|Designator=69|PinName_PositionConglomerate=16|Name_CustomFontID=1|PinDesignator_PositionConglomerate=16|Designator_CustomFontID=1|PinPropagationDelay=0.000000E+000
|RECORD=2|OwnerIndex=1063|OwnerPartId=1|Electrical=4|PinConglomerate=48|PinLength=20|Location.X=750|Location.Y=180|Name=71|Designator=71|PinName_PositionConglomerate=16|Name_CustomFontID=1|PinDesignator_PositionConglomerate=16|Designator_CustomFontID=1|PinPropagationDelay=0.000000E+000
|RECORD=2|OwnerIndex=1063|OwnerPartId=1|Electrical=4|PinConglomerate=48|PinLength=20|Location.X=750|Location.Y=160|Name=73|Designator=73|PinName_PositionConglomerate=16|Name_CustomFontID=1|PinDesignator_PositionConglomerate=16|Designator_CustomFontID=1|PinPropagationDelay=0.000000E+000
|RECORD=2|OwnerIndex=1063|OwnerPartId=1|Electrical=4|PinConglomerate=48|PinLength=20|Location.X=750|Location.Y=140|Name=75|Designator=75|PinName_PositionConglomerate=16|Name_CustomFontID=1|PinDesignator_PositionConglomerate=16|Designator_CustomFontID=1|PinPropagationDelay=0.000000E+000
|RECORD=2|OwnerIndex=1063|OwnerPartId=1|Electrical=4|PinConglomerate=48|PinLength=20|Location.X=750|Location.Y=120|Name=MNT 2|Designator=77|PinName_PositionConglomerate=16|Name_CustomFontID=1|PinDesignator_PositionConglomerate=16|Designator_CustomFontID=1|PinPropagationDelay=0.000000E+000
|RECORD=14|OwnerIndex=1063|IsNotAccesible=T|IndexInSheet=141|OwnerPartId=2|Location.X=700|Location.Y=120|Corner.X=750|Corner.Y=820|LineWidth=1|Color=128|AreaColor=11599871|IsSolid=T
|RECORD=8|OwnerIndex=1063|IsNotAccesible=T|IndexInSheet=142|OwnerPartId=2|Location.X=725|Location.Y=800|Radius=3|SecondaryRadius=3|LineWidth=1|Color=16711680
|RECORD=13|OwnerIndex=1063|IsNotAccesible=T|IndexInSheet=143|OwnerPartId=2|Location.X=728|Location.Y=800|Corner.X=750|Corner.Y=800|LineWidth=1|Color=16711680
|RECORD=8|OwnerIndex=1063|IsNotAccesible=T|IndexInSheet=144|OwnerPartId=2|Location.X=725|Location.Y=780|Radius=3|SecondaryRadius=3|LineWidth=1|Color=16711680
|RECORD=13|OwnerIndex=1063|IsNotAccesible=T|IndexInSheet=145|OwnerPartId=2|Location.X=728|Location.Y=780|Corner.X=750|Corner.Y=780|LineWidth=1|Color=16711680
|RECORD=8|OwnerIndex=1063|IsNotAccesible=T|IndexInSheet=146|OwnerPartId=2|Location.X=725|Location.Y=760|Radius=3|SecondaryRadius=3|LineWidth=1|Color=16711680
|RECORD=13|OwnerIndex=1063|IsNotAccesible=T|IndexInSheet=147|OwnerPartId=2|Location.X=728|Location.Y=760|Corner.X=750|Corner.Y=760|LineWidth=1|Color=16711680
|RECORD=8|OwnerIndex=1063|IsNotAccesible=T|IndexInSheet=148|OwnerPartId=2|Location.X=725|Location.Y=740|Radius=3|SecondaryRadius=3|LineWidth=1|Color=16711680
|RECORD=13|OwnerIndex=1063|IsNotAccesible=T|IndexInSheet=149|OwnerPartId=2|Location.X=728|Location.Y=740|Corner.X=750|Corner.Y=740|LineWidth=1|Color=16711680
|RECORD=8|OwnerIndex=1063|IsNotAccesible=T|IndexInSheet=150|OwnerPartId=2|Location.X=725|Location.Y=720|Radius=3|SecondaryRadius=3|LineWidth=1|Color=16711680
|RECORD=13|OwnerIndex=1063|IsNotAccesible=T|IndexInSheet=151|OwnerPartId=2|Location.X=728|Location.Y=720|Corner.X=750|Corner.Y=720|LineWidth=1|Color=16711680
|RECORD=8|OwnerIndex=1063|IsNotAccesible=T|IndexInSheet=152|OwnerPartId=2|Location.X=725|Location.Y=700|Radius=3|SecondaryRadius=3|LineWidth=1|Color=16711680
|RECORD=13|OwnerIndex=1063|IsNotAccesible=T|IndexInSheet=153|OwnerPartId=2|Location.X=728|Location.Y=700|Corner.X=750|Corner.Y=700|LineWidth=1|Color=16711680
|RECORD=8|OwnerIndex=1063|IsNotAccesible=T|IndexInSheet=154|OwnerPartId=2|Location.X=725|Location.Y=680|Radius=3|SecondaryRadius=3|LineWidth=1|Color=16711680
|RECORD=13|OwnerIndex=1063|IsNotAccesible=T|IndexInSheet=155|OwnerPartId=2|Location.X=728|Location.Y=680|Corner.X=750|Corner.Y=680|LineWidth=1|Color=16711680
|RECORD=8|OwnerIndex=1063|IsNotAccesible=T|IndexInSheet=156|OwnerPartId=2|Location.X=725|Location.Y=660|Radius=3|SecondaryRadius=3|LineWidth=1|Color=16711680
|RECORD=13|OwnerIndex=1063|IsNotAccesible=T|IndexInSheet=157|OwnerPartId=2|Location.X=728|Location.Y=660|Corner.X=750|Corner.Y=660|LineWidth=1|Color=16711680
|RECORD=8|OwnerIndex=1063|IsNotAccesible=T|IndexInSheet=158|OwnerPartId=2|Location.X=725|Location.Y=640|Radius=3|SecondaryRadius=3|LineWidth=1|Color=16711680
|RECORD=13|OwnerIndex=1063|IsNotAccesible=T|IndexInSheet=159|OwnerPartId=2|Location.X=728|Location.Y=640|Corner.X=750|Corner.Y=640|LineWidth=1|Color=16711680
|RECORD=8|OwnerIndex=1063|IsNotAccesible=T|IndexInSheet=160|OwnerPartId=2|Location.X=725|Location.Y=620|Radius=3|SecondaryRadius=3|LineWidth=1|Color=16711680
|RECORD=13|OwnerIndex=1063|IsNotAccesible=T|IndexInSheet=161|OwnerPartId=2|Location.X=728|Location.Y=620|Corner.X=750|Corner.Y=620|LineWidth=1|Color=16711680
|RECORD=8|OwnerIndex=1063|IsNotAccesible=T|IndexInSheet=162|OwnerPartId=2|Location.X=725|Location.Y=600|Radius=3|SecondaryRadius=3|LineWidth=1|Color=16711680
|RECORD=13|OwnerIndex=1063|IsNotAccesible=T|IndexInSheet=163|OwnerPartId=2|Location.X=728|Location.Y=600|Corner.X=750|Corner.Y=600|LineWidth=1|Color=16711680
|RECORD=8|OwnerIndex=1063|IsNotAccesible=T|IndexInSheet=164|OwnerPartId=2|Location.X=725|Location.Y=580|Radius=3|SecondaryRadius=3|LineWidth=1|Color=16711680
|RECORD=13|OwnerIndex=1063|IsNotAccesible=T|IndexInSheet=165|OwnerPartId=2|Location.X=728|Location.Y=580|Corner.X=750|Corner.Y=580|LineWidth=1|Color=16711680
|RECORD=8|OwnerIndex=1063|IsNotAccesible=T|IndexInSheet=166|OwnerPartId=2|Location.X=725|Location.Y=560|Radius=3|SecondaryRadius=3|LineWidth=1|Color=16711680
|RECORD=13|OwnerIndex=1063|IsNotAccesible=T|IndexInSheet=167|OwnerPartId=2|Location.X=728|Location.Y=560|Corner.X=750|Corner.Y=560|LineWidth=1|Color=16711680
|RECORD=8|OwnerIndex=1063|IsNotAccesible=T|IndexInSheet=168|OwnerPartId=2|Location.X=725|Location.Y=540|Radius=3|SecondaryRadius=3|LineWidth=1|Color=16711680
|RECORD=13|OwnerIndex=1063|IsNotAccesible=T|IndexInSheet=169|OwnerPartId=2|Location.X=728|Location.Y=540|Corner.X=750|Corner.Y=540|LineWidth=1|Color=16711680
|RECORD=8|OwnerIndex=1063|IsNotAccesible=T|IndexInSheet=170|OwnerPartId=2|Location.X=725|Location.Y=520|Radius=3|SecondaryRadius=3|LineWidth=1|Color=16711680
|RECORD=13|OwnerIndex=1063|IsNotAccesible=T|IndexInSheet=171|OwnerPartId=2|Location.X=728|Location.Y=520|Corner.X=750|Corner.Y=520|LineWidth=1|Color=16711680
|RECORD=8|OwnerIndex=1063|IsNotAccesible=T|IndexInSheet=172|OwnerPartId=2|Location.X=725|Location.Y=500|Radius=3|SecondaryRadius=3|LineWidth=1|Color=16711680
|RECORD=13|OwnerIndex=1063|IsNotAccesible=T|IndexInSheet=173|OwnerPartId=2|Location.X=728|Location.Y=500|Corner.X=750|Corner.Y=500|LineWidth=1|Color=16711680
|RECORD=8|OwnerIndex=1063|IsNotAccesible=T|IndexInSheet=174|OwnerPartId=2|Location.X=725|Location.Y=480|Radius=3|SecondaryRadius=3|LineWidth=1|Color=16711680
|RECORD=13|OwnerIndex=1063|IsNotAccesible=T|IndexInSheet=175|OwnerPartId=2|Location.X=728|Location.Y=480|Corner.X=750|Corner.Y=480|LineWidth=1|Color=16711680
|RECORD=8|OwnerIndex=1063|IsNotAccesible=T|IndexInSheet=176|OwnerPartId=2|Location.X=725|Location.Y=460|Radius=3|SecondaryRadius=3|LineWidth=1|Color=16711680
|RECORD=13|OwnerIndex=1063|IsNotAccesible=T|IndexInSheet=177|OwnerPartId=2|Location.X=728|Location.Y=460|Corner.X=750|Corner.Y=460|LineWidth=1|Color=16711680
|RECORD=8|OwnerIndex=1063|IsNotAccesible=T|IndexInSheet=178|OwnerPartId=2|Location.X=725|Location.Y=440|Radius=3|SecondaryRadius=3|LineWidth=1|Color=16711680
|RECORD=13|OwnerIndex=1063|IsNotAccesible=T|IndexInSheet=179|OwnerPartId=2|Location.X=728|Location.Y=440|Corner.X=750|Corner.Y=440|LineWidth=1|Color=16711680
|RECORD=8|OwnerIndex=1063|IsNotAccesible=T|IndexInSheet=180|OwnerPartId=2|Location.X=725|Location.Y=420|Radius=3|SecondaryRadius=3|LineWidth=1|Color=16711680
|RECORD=13|OwnerIndex=1063|IsNotAccesible=T|IndexInSheet=181|OwnerPartId=2|Location.X=728|Location.Y=420|Corner.X=750|Corner.Y=420|LineWidth=1|Color=16711680
|RECORD=8|OwnerIndex=1063|IsNotAccesible=T|IndexInSheet=182|OwnerPartId=2|Location.X=725|Location.Y=400|Radius=3|SecondaryRadius=3|LineWidth=1|Color=16711680
|RECORD=13|OwnerIndex=1063|IsNotAccesible=T|IndexInSheet=183|OwnerPartId=2|Location.X=728|Location.Y=400|Corner.X=750|Corner.Y=400|LineWidth=1|Color=16711680
|RECORD=8|OwnerIndex=1063|IsNotAccesible=T|IndexInSheet=184|OwnerPartId=2|Location.X=725|Location.Y=380|Radius=3|SecondaryRadius=3|LineWidth=1|Color=16711680
|RECORD=13|OwnerIndex=1063|IsNotAccesible=T|IndexInSheet=185|OwnerPartId=2|Location.X=728|Location.Y=380|Corner.X=750|Corner.Y=380|LineWidth=1|Color=16711680
|RECORD=8|OwnerIndex=1063|IsNotAccesible=T|IndexInSheet=186|OwnerPartId=2|Location.X=725|Location.Y=360|Radius=3|SecondaryRadius=3|LineWidth=1|Color=16711680
|RECORD=13|OwnerIndex=1063|IsNotAccesible=T|IndexInSheet=187|OwnerPartId=2|Location.X=728|Location.Y=360|Corner.X=750|Corner.Y=360|LineWidth=1|Color=16711680
|RECORD=8|OwnerIndex=1063|IsNotAccesible=T|IndexInSheet=188|OwnerPartId=2|Location.X=725|Location.Y=340|Radius=3|SecondaryRadius=3|LineWidth=1|Color=16711680
|RECORD=13|OwnerIndex=1063|IsNotAccesible=T|IndexInSheet=189|OwnerPartId=2|Location.X=728|Location.Y=340|Corner.X=750|Corner.Y=340|LineWidth=1|Color=16711680
|RECORD=8|OwnerIndex=1063|IsNotAccesible=T|IndexInSheet=190|OwnerPartId=2|Location.X=725|Location.Y=320|Radius=3|SecondaryRadius=3|LineWidth=1|Color=16711680
|RECORD=13|OwnerIndex=1063|IsNotAccesible=T|IndexInSheet=191|OwnerPartId=2|Location.X=728|Location.Y=320|Corner.X=750|Corner.Y=320|LineWidth=1|Color=16711680
|RECORD=8|OwnerIndex=1063|IsNotAccesible=T|IndexInSheet=192|OwnerPartId=2|Location.X=725|Location.Y=300|Radius=3|SecondaryRadius=3|LineWidth=1|Color=16711680
|RECORD=13|OwnerIndex=1063|IsNotAccesible=T|IndexInSheet=193|OwnerPartId=2|Location.X=728|Location.Y=300|Corner.X=750|Corner.Y=300|LineWidth=1|Color=16711680
|RECORD=8|OwnerIndex=1063|IsNotAccesible=T|IndexInSheet=194|OwnerPartId=2|Location.X=725|Location.Y=280|Radius=3|SecondaryRadius=3|LineWidth=1|Color=16711680
|RECORD=13|OwnerIndex=1063|IsNotAccesible=T|IndexInSheet=195|OwnerPartId=2|Location.X=728|Location.Y=280|Corner.X=750|Corner.Y=280|LineWidth=1|Color=16711680
|RECORD=8|OwnerIndex=1063|IsNotAccesible=T|IndexInSheet=196|OwnerPartId=2|Location.X=725|Location.Y=260|Radius=3|SecondaryRadius=3|LineWidth=1|Color=16711680
|RECORD=13|OwnerIndex=1063|IsNotAccesible=T|IndexInSheet=197|OwnerPartId=2|Location.X=728|Location.Y=260|Corner.X=750|Corner.Y=260|LineWidth=1|Color=16711680
|RECORD=8|OwnerIndex=1063|IsNotAccesible=T|IndexInSheet=198|OwnerPartId=2|Location.X=725|Location.Y=240|Radius=3|SecondaryRadius=3|LineWidth=1|Color=16711680
|RECORD=13|OwnerIndex=1063|IsNotAccesible=T|IndexInSheet=199|OwnerPartId=2|Location.X=728|Location.Y=240|Corner.X=750|Corner.Y=240|LineWidth=1|Color=16711680
|RECORD=8|OwnerIndex=1063|IsNotAccesible=T|IndexInSheet=200|OwnerPartId=2|Location.X=725|Location.Y=220|Radius=3|SecondaryRadius=3|LineWidth=1|Color=16711680
|RECORD=13|OwnerIndex=1063|IsNotAccesible=T|IndexInSheet=201|OwnerPartId=2|Location.X=728|Location.Y=220|Corner.X=750|Corner.Y=220|LineWidth=1|Color=16711680
|RECORD=8|OwnerIndex=1063|IsNotAccesible=T|IndexInSheet=202|OwnerPartId=2|Location.X=725|Location.Y=200|Radius=3|SecondaryRadius=3|LineWidth=1|Color=16711680
|RECORD=13|OwnerIndex=1063|IsNotAccesible=T|IndexInSheet=203|OwnerPartId=2|Location.X=728|Location.Y=200|Corner.X=750|Corner.Y=200|LineWidth=1|Color=16711680
|RECORD=8|OwnerIndex=1063|IsNotAccesible=T|IndexInSheet=204|OwnerPartId=2|Location.X=725|Location.Y=180|Radius=3|SecondaryRadius=3|LineWidth=1|Color=16711680
|RECORD=13|OwnerIndex=1063|IsNotAccesible=T|IndexInSheet=205|OwnerPartId=2|Location.X=728|Location.Y=180|Corner.X=750|Corner.Y=180|LineWidth=1|Color=16711680
|RECORD=8|OwnerIndex=1063|IsNotAccesible=T|IndexInSheet=206|OwnerPartId=2|Location.X=725|Location.Y=160|Radius=3|SecondaryRadius=3|LineWidth=1|Color=16711680
|RECORD=13|OwnerIndex=1063|IsNotAccesible=T|IndexInSheet=207|OwnerPartId=2|Location.X=728|Location.Y=160|Corner.X=750|Corner.Y=160|LineWidth=1|Color=16711680
|RECORD=8|OwnerIndex=1063|IsNotAccesible=T|IndexInSheet=208|OwnerPartId=2|Location.X=725|Location.Y=140|Radius=3|SecondaryRadius=3|LineWidth=1|Color=16711680
|RECORD=13|OwnerIndex=1063|IsNotAccesible=T|IndexInSheet=209|OwnerPartId=2|Location.X=728|Location.Y=140|Corner.X=750|Corner.Y=140|LineWidth=1|Color=16711680
|RECORD=4|OwnerIndex=1063|IsNotAccesible=T|IndexInSheet=210|OwnerPartId=2|Location.X=743|Location.Y=812|Justification=8|Color=8388608|FontID=1|Text=2
|RECORD=4|OwnerIndex=1063|IsNotAccesible=T|IndexInSheet=211|OwnerPartId=2|Location.X=743|Location.Y=792|Justification=8|Color=8388608|FontID=1|Text=4
|RECORD=4|OwnerIndex=1063|IsNotAccesible=T|IndexInSheet=212|OwnerPartId=2|Location.X=743|Location.Y=772|Justification=8|Color=8388608|FontID=1|Text=6
|RECORD=4|OwnerIndex=1063|IsNotAccesible=T|IndexInSheet=213|OwnerPartId=2|Location.X=743|Location.Y=752|Justification=8|Color=8388608|FontID=1|Text=8
|RECORD=4|OwnerIndex=1063|IsNotAccesible=T|IndexInSheet=214|OwnerPartId=2|Location.X=743|Location.Y=732|Justification=8|Color=8388608|FontID=1|Text=10
|RECORD=4|OwnerIndex=1063|IsNotAccesible=T|IndexInSheet=215|OwnerPartId=2|Location.X=743|Location.Y=712|Justification=8|Color=8388608|FontID=1|Text=20
|RECORD=4|OwnerIndex=1063|IsNotAccesible=T|IndexInSheet=216|OwnerPartId=2|Location.X=743|Location.Y=692|Justification=8|Color=8388608|FontID=1|Text=22
|RECORD=4|OwnerIndex=1063|IsNotAccesible=T|IndexInSheet=217|OwnerPartId=2|Location.X=743|Location.Y=672|Justification=8|Color=8388608|FontID=1|Text=24
|RECORD=4|OwnerIndex=1063|IsNotAccesible=T|IndexInSheet=218|OwnerPartId=2|Location.X=743|Location.Y=652|Justification=8|Color=8388608|FontID=1|Text=26
|RECORD=4|OwnerIndex=1063|IsNotAccesible=T|IndexInSheet=219|OwnerPartId=2|Location.X=743|Location.Y=632|Justification=8|Color=8388608|FontID=1|Text=28
|RECORD=4|OwnerIndex=1063|IsNotAccesible=T|IndexInSheet=220|OwnerPartId=2|Location.X=743|Location.Y=612|Justification=8|Color=8388608|FontID=1|Text=30
|RECORD=4|OwnerIndex=1063|IsNotAccesible=T|IndexInSheet=221|OwnerPartId=2|Location.X=743|Location.Y=592|Justification=8|Color=8388608|FontID=1|Text=32
|RECORD=4|OwnerIndex=1063|IsNotAccesible=T|IndexInSheet=222|OwnerPartId=2|Location.X=743|Location.Y=572|Justification=8|Color=8388608|FontID=1|Text=34
|RECORD=4|OwnerIndex=1063|IsNotAccesible=T|IndexInSheet=223|OwnerPartId=2|Location.X=743|Location.Y=552|Justification=8|Color=8388608|FontID=1|Text=36
|RECORD=4|OwnerIndex=1063|IsNotAccesible=T|IndexInSheet=224|OwnerPartId=2|Location.X=743|Location.Y=532|Justification=8|Color=8388608|FontID=1|Text=38
|RECORD=4|OwnerIndex=1063|IsNotAccesible=T|IndexInSheet=225|OwnerPartId=2|Location.X=743|Location.Y=512|Justification=8|Color=8388608|FontID=1|Text=40
|RECORD=4|OwnerIndex=1063|IsNotAccesible=T|IndexInSheet=226|OwnerPartId=2|Location.X=743|Location.Y=492|Justification=8|Color=8388608|FontID=1|Text=42
|RECORD=4|OwnerIndex=1063|IsNotAccesible=T|IndexInSheet=227|OwnerPartId=2|Location.X=743|Location.Y=472|Justification=8|Color=8388608|FontID=1|Text=44
|RECORD=4|OwnerIndex=1063|IsNotAccesible=T|IndexInSheet=228|OwnerPartId=2|Location.X=743|Location.Y=452|Justification=8|Color=8388608|FontID=1|Text=46
|RECORD=4|OwnerIndex=1063|IsNotAccesible=T|IndexInSheet=229|OwnerPartId=2|Location.X=743|Location.Y=432|Justification=8|Color=8388608|FontID=1|Text=48
|RECORD=4|OwnerIndex=1063|IsNotAccesible=T|IndexInSheet=230|OwnerPartId=2|Location.X=743|Location.Y=412|Justification=8|Color=8388608|FontID=1|Text=50
|RECORD=4|OwnerIndex=1063|IsNotAccesible=T|IndexInSheet=231|OwnerPartId=2|Location.X=743|Location.Y=392|Justification=8|Color=8388608|FontID=1|Text=52
|RECORD=4|OwnerIndex=1063|IsNotAccesible=T|IndexInSheet=232|OwnerPartId=2|Location.X=743|Location.Y=372|Justification=8|Color=8388608|FontID=1|Text=54
|RECORD=4|OwnerIndex=1063|IsNotAccesible=T|IndexInSheet=233|OwnerPartId=2|Location.X=743|Location.Y=352|Justification=8|Color=8388608|FontID=1|Text=56
|RECORD=4|OwnerIndex=1063|IsNotAccesible=T|IndexInSheet=234|OwnerPartId=2|Location.X=743|Location.Y=332|Justification=8|Color=8388608|FontID=1|Text=58
|RECORD=4|OwnerIndex=1063|IsNotAccesible=T|IndexInSheet=235|OwnerPartId=2|Location.X=743|Location.Y=312|Justification=8|Color=8388608|FontID=1|Text=60
|RECORD=4|OwnerIndex=1063|IsNotAccesible=T|IndexInSheet=236|OwnerPartId=2|Location.X=743|Location.Y=292|Justification=8|Color=8388608|FontID=1|Text=62
|RECORD=4|OwnerIndex=1063|IsNotAccesible=T|IndexInSheet=237|OwnerPartId=2|Location.X=743|Location.Y=272|Justification=8|Color=8388608|FontID=1|Text=64
|RECORD=4|OwnerIndex=1063|IsNotAccesible=T|IndexInSheet=238|OwnerPartId=2|Location.X=743|Location.Y=252|Justification=8|Color=8388608|FontID=1|Text=66
|RECORD=4|OwnerIndex=1063|IsNotAccesible=T|IndexInSheet=239|OwnerPartId=2|Location.X=743|Location.Y=232|Justification=8|Color=8388608|FontID=1|Text=68
|RECORD=4|OwnerIndex=1063|IsNotAccesible=T|IndexInSheet=240|OwnerPartId=2|Location.X=743|Location.Y=212|Justification=8|Color=8388608|FontID=1|Text=70
|RECORD=4|OwnerIndex=1063|IsNotAccesible=T|IndexInSheet=241|OwnerPartId=2|Location.X=743|Location.Y=192|Justification=8|Color=8388608|FontID=1|Text=72
|RECORD=4|OwnerIndex=1063|IsNotAccesible=T|IndexInSheet=242|OwnerPartId=2|Location.X=743|Location.Y=172|Justification=8|Color=8388608|FontID=1|Text=74
|RECORD=4|OwnerIndex=1063|IsNotAccesible=T|IndexInSheet=243|OwnerPartId=2|Location.X=743|Location.Y=152|Justification=8|Color=8388608|FontID=1|Text=MNT 1
|RECORD=2|OwnerIndex=1063|OwnerPartId=2|Electrical=4|PinConglomerate=48|PinLength=20|Location.X=750|Location.Y=800|Name=2|Designator=2|PinName_PositionConglomerate=16|Name_CustomFontID=1|PinDesignator_PositionConglomerate=16|Designator_CustomFontID=1|PinPropagationDelay=0.000000E+000
|RECORD=2|OwnerIndex=1063|OwnerPartId=2|Electrical=4|PinConglomerate=48|PinLength=20|Location.X=750|Location.Y=780|Name=4|Designator=4|PinName_PositionConglomerate=16|Name_CustomFontID=1|PinDesignator_PositionConglomerate=16|Designator_CustomFontID=1|PinPropagationDelay=0.000000E+000
|RECORD=2|OwnerIndex=1063|OwnerPartId=2|Electrical=4|PinConglomerate=48|PinLength=20|Location.X=750|Location.Y=760|Name=6|Designator=6|PinName_PositionConglomerate=16|Name_CustomFontID=1|PinDesignator_PositionConglomerate=16|Designator_CustomFontID=1|PinPropagationDelay=0.000000E+000
|RECORD=2|OwnerIndex=1063|OwnerPartId=2|Electrical=4|PinConglomerate=48|PinLength=20|Location.X=750|Location.Y=740|Name=8|Designator=8|PinName_PositionConglomerate=16|Name_CustomFontID=1|PinDesignator_PositionConglomerate=16|Designator_CustomFontID=1|PinPropagationDelay=0.000000E+000
|RECORD=2|OwnerIndex=1063|OwnerPartId=2|Electrical=4|PinConglomerate=48|PinLength=20|Location.X=750|Location.Y=720|Name=10|Designator=10|PinName_PositionConglomerate=16|Name_CustomFontID=1|PinDesignator_PositionConglomerate=16|Designator_CustomFontID=1|PinPropagationDelay=0.000000E+000
|RECORD=2|OwnerIndex=1063|OwnerPartId=2|Electrical=4|PinConglomerate=48|PinLength=20|Location.X=750|Location.Y=700|Name=20|Designator=20|PinName_PositionConglomerate=16|Name_CustomFontID=1|PinDesignator_PositionConglomerate=16|Designator_CustomFontID=1|PinPropagationDelay=0.000000E+000
|RECORD=2|OwnerIndex=1063|OwnerPartId=2|Electrical=4|PinConglomerate=48|PinLength=20|Location.X=750|Location.Y=680|Name=22|Designator=22|PinName_PositionConglomerate=16|Name_CustomFontID=1|PinDesignator_PositionConglomerate=16|Designator_CustomFontID=1|PinPropagationDelay=0.000000E+000
|RECORD=2|OwnerIndex=1063|OwnerPartId=2|Electrical=4|PinConglomerate=48|PinLength=20|Location.X=750|Location.Y=660|Name=24|Designator=24|PinName_PositionConglomerate=16|Name_CustomFontID=1|PinDesignator_PositionConglomerate=16|Designator_CustomFontID=1|PinPropagationDelay=0.000000E+000
|RECORD=2|OwnerIndex=1063|OwnerPartId=2|Electrical=4|PinConglomerate=48|PinLength=20|Location.X=750|Location.Y=640|Name=26|Designator=26|PinName_PositionConglomerate=16|Name_CustomFontID=1|PinDesignator_PositionConglomerate=16|Designator_CustomFontID=1|PinPropagationDelay=0.000000E+000
|RECORD=2|OwnerIndex=1063|OwnerPartId=2|Electrical=4|PinConglomerate=48|PinLength=20|Location.X=750|Location.Y=620|Name=28|Designator=28|PinName_PositionConglomerate=16|Name_CustomFontID=1|PinDesignator_PositionConglomerate=16|Designator_CustomFontID=1|PinPropagationDelay=0.000000E+000
|RECORD=2|OwnerIndex=1063|OwnerPartId=2|Electrical=4|PinConglomerate=48|PinLength=20|Location.X=750|Location.Y=600|Name=30|Designator=30|PinName_PositionConglomerate=16|Name_CustomFontID=1|PinDesignator_PositionConglomerate=16|Designator_CustomFontID=1|PinPropagationDelay=0.000000E+000
|RECORD=2|OwnerIndex=1063|OwnerPartId=2|Electrical=4|PinConglomerate=48|PinLength=20|Location.X=750|Location.Y=580|Name=32|Designator=32|PinName_PositionConglomerate=16|Name_CustomFontID=1|PinDesignator_PositionConglomerate=16|Designator_CustomFontID=1|PinPropagationDelay=0.000000E+000
|RECORD=2|OwnerIndex=1063|OwnerPartId=2|Electrical=4|PinConglomerate=48|PinLength=20|Location.X=750|Location.Y=560|Name=34|Designator=34|PinName_PositionConglomerate=16|Name_CustomFontID=1|PinDesignator_PositionConglomerate=16|Designator_CustomFontID=1|PinPropagationDelay=0.000000E+000
|RECORD=2|OwnerIndex=1063|OwnerPartId=2|Electrical=4|PinConglomerate=48|PinLength=20|Location.X=750|Location.Y=540|Name=36|Designator=36|PinName_PositionConglomerate=16|Name_CustomFontID=1|PinDesignator_PositionConglomerate=16|Designator_CustomFontID=1|PinPropagationDelay=0.000000E+000
|RECORD=2|OwnerIndex=1063|OwnerPartId=2|Electrical=4|PinConglomerate=48|PinLength=20|Location.X=750|Location.Y=520|Name=38|Designator=38|PinName_PositionConglomerate=16|Name_CustomFontID=1|PinDesignator_PositionConglomerate=16|Designator_CustomFontID=1|PinPropagationDelay=0.000000E+000
|RECORD=2|OwnerIndex=1063|OwnerPartId=2|Electrical=4|PinConglomerate=48|PinLength=20|Location.X=750|Location.Y=500|Name=40|Designator=40|PinName_PositionConglomerate=16|Name_CustomFontID=1|PinDesignator_PositionConglomerate=16|Designator_CustomFontID=1|PinPropagationDelay=0.000000E+000
|RECORD=2|OwnerIndex=1063|OwnerPartId=2|Electrical=4|PinConglomerate=48|PinLength=20|Location.X=750|Location.Y=480|Name=42|Designator=42|PinName_PositionConglomerate=16|Name_CustomFontID=1|PinDesignator_PositionConglomerate=16|Designator_CustomFontID=1|PinPropagationDelay=0.000000E+000
|RECORD=2|OwnerIndex=1063|OwnerPartId=2|Electrical=4|PinConglomerate=48|PinLength=20|Location.X=750|Location.Y=460|Name=44|Designator=44|PinName_PositionConglomerate=16|Name_CustomFontID=1|PinDesignator_PositionConglomerate=16|Designator_CustomFontID=1|PinPropagationDelay=0.000000E+000
|RECORD=2|OwnerIndex=1063|OwnerPartId=2|Electrical=4|PinConglomerate=48|PinLength=20|Location.X=750|Location.Y=440|Name=46|Designator=46|PinName_PositionConglomerate=16|Name_CustomFontID=1|PinDesignator_PositionConglomerate=16|Designator_CustomFontID=1|PinPropagationDelay=0.000000E+000
|RECORD=2|OwnerIndex=1063|OwnerPartId=2|Electrical=4|PinConglomerate=48|PinLength=20|Location.X=750|Location.Y=420|Name=48|Designator=48|PinName_PositionConglomerate=16|Name_CustomFontID=1|PinDesignator_PositionConglomerate=16|Designator_CustomFontID=1|PinPropagationDelay=0.000000E+000
|RECORD=2|OwnerIndex=1063|OwnerPartId=2|Electrical=4|PinConglomerate=48|PinLength=20|Location.X=750|Location.Y=400|Name=50|Designator=50|PinName_PositionConglomerate=16|Name_CustomFontID=1|PinDesignator_PositionConglomerate=16|Designator_CustomFontID=1|PinPropagationDelay=0.000000E+000
|RECORD=2|OwnerIndex=1063|OwnerPartId=2|Electrical=4|PinConglomerate=48|PinLength=20|Location.X=750|Location.Y=380|Name=52|Designator=52|PinName_PositionConglomerate=16|Name_CustomFontID=1|PinDesignator_PositionConglomerate=16|Designator_CustomFontID=1|PinPropagationDelay=0.000000E+000
|RECORD=2|OwnerIndex=1063|OwnerPartId=2|Electrical=4|PinConglomerate=48|PinLength=20|Location.X=750|Location.Y=360|Name=54|Designator=54|PinName_PositionConglomerate=16|Name_CustomFontID=1|PinDesignator_PositionConglomerate=16|Designator_CustomFontID=1|PinPropagationDelay=0.000000E+000
|RECORD=2|OwnerIndex=1063|OwnerPartId=2|Electrical=4|PinConglomerate=48|PinLength=20|Location.X=750|Location.Y=340|Name=56|Designator=56|PinName_PositionConglomerate=16|Name_CustomFontID=1|PinDesignator_PositionConglomerate=16|Designator_CustomFontID=1|PinPropagationDelay=0.000000E+000
|RECORD=2|OwnerIndex=1063|OwnerPartId=2|Electrical=4|PinConglomerate=48|PinLength=20|Location.X=750|Location.Y=320|Name=58|Designator=58|PinName_PositionConglomerate=16|Name_CustomFontID=1|PinDesignator_PositionConglomerate=16|Designator_CustomFontID=1|PinPropagationDelay=0.000000E+000
|RECORD=2|OwnerIndex=1063|OwnerPartId=2|Electrical=4|PinConglomerate=48|PinLength=20|Location.X=750|Location.Y=300|Name=60|Designator=60|PinName_PositionConglomerate=16|Name_CustomFontID=1|PinDesignator_PositionConglomerate=16|Designator_CustomFontID=1|PinPropagationDelay=0.000000E+000
|RECORD=2|OwnerIndex=1063|OwnerPartId=2|Electrical=4|PinConglomerate=48|PinLength=20|Location.X=750|Location.Y=280|Name=62|Designator=62|PinName_PositionConglomerate=16|Name_CustomFontID=1|PinDesignator_PositionConglomerate=16|Designator_CustomFontID=1|PinPropagationDelay=0.000000E+000
|RECORD=2|OwnerIndex=1063|OwnerPartId=2|Electrical=4|PinConglomerate=48|PinLength=20|Location.X=750|Location.Y=260|Name=64|Designator=64|PinName_PositionConglomerate=16|Name_CustomFontID=1|PinDesignator_PositionConglomerate=16|Designator_CustomFontID=1|PinPropagationDelay=0.000000E+000
|RECORD=2|OwnerIndex=1063|OwnerPartId=2|Electrical=4|PinConglomerate=48|PinLength=20|Location.X=750|Location.Y=240|Name=66|Designator=66|PinName_PositionConglomerate=16|Name_CustomFontID=1|PinDesignator_PositionConglomerate=16|Designator_CustomFontID=1|PinPropagationDelay=0.000000E+000
|RECORD=2|OwnerIndex=1063|OwnerPartId=2|Electrical=4|PinConglomerate=48|PinLength=20|Location.X=750|Location.Y=220|Name=68|Designator=68|PinName_PositionConglomerate=16|Name_CustomFontID=1|PinDesignator_PositionConglomerate=16|Designator_CustomFontID=1|PinPropagationDelay=0.000000E+000
|RECORD=2|OwnerIndex=1063|OwnerPartId=2|Electrical=4|PinConglomerate=48|PinLength=20|Location.X=750|Location.Y=200|Name=70|Designator=70|PinName_PositionConglomerate=16|Name_CustomFontID=1|PinDesignator_PositionConglomerate=16|Designator_CustomFontID=1|PinPropagationDelay=0.000000E+000
|RECORD=2|OwnerIndex=1063|OwnerPartId=2|Electrical=4|PinConglomerate=48|PinLength=20|Location.X=750|Location.Y=180|Name=72|Designator=72|PinName_PositionConglomerate=16|Name_CustomFontID=1|PinDesignator_PositionConglomerate=16|Designator_CustomFontID=1|PinPropagationDelay=0.000000E+000
|RECORD=2|OwnerIndex=1063|OwnerPartId=2|Electrical=4|PinConglomerate=48|PinLength=20|Location.X=750|Location.Y=160|Name=74|Designator=74|PinName_PositionConglomerate=16|Name_CustomFontID=1|PinDesignator_PositionConglomerate=16|Designator_CustomFontID=1|PinPropagationDelay=0.000000E+000
|RECORD=2|OwnerIndex=1063|OwnerPartId=2|Electrical=4|PinConglomerate=48|PinLength=20|Location.X=750|Location.Y=140|Name=MNT 1|Designator=76|PinName_PositionConglomerate=16|Name_CustomFontID=1|PinDesignator_PositionConglomerate=16|Designator_CustomFontID=1|PinPropagationDelay=0.000000E+000
|RECORD=41|OwnerIndex=1063|IndexInSheet=278|OwnerPartId=-1|Location.X=700|Location.Y=820|Color=8388608|FontID=1|IsHidden=T|Text=500mA|Name=Contact Current Rating
|RECORD=41|OwnerIndex=1063|IndexInSheet=279|OwnerPartId=-1|Location.X=700|Location.Y=820|Color=8388608|FontID=1|IsHidden=T|Text=67|Name=Number of Contacts
|RECORD=41|OwnerIndex=1063|IndexInSheet=280|OwnerPartId=-1|Location.X=700|Location.Y=820|Color=8388608|FontID=1|IsHidden=T|Text=Right Angle|Name=Orientation
|RECORD=41|OwnerIndex=1063|IndexInSheet=281|OwnerPartId=-1|Location.X=700|Location.Y=820|Color=8388608|FontID=1|IsHidden=T|Text=0.862inch|Name=Length
|RECORD=41|OwnerIndex=1063|IndexInSheet=282|OwnerPartId=-1|Location.X=700|Location.Y=820|Color=8388608|FontID=1|IsHidden=T|Text=No|Name=Radiation Hardening
|RECORD=41|OwnerIndex=1063|IndexInSheet=283|OwnerPartId=-1|Location.X=700|Location.Y=820|Color=8388608|FontID=1|IsHidden=T|Text=Right Angle|Name=PCB Mounting Orientation
|RECORD=41|OwnerIndex=1063|IndexInSheet=284|OwnerPartId=-1|Location.X=700|Location.Y=820|Color=8388608|FontID=1|IsHidden=T|Text=Surface Mount|Name=Mount
|RECORD=41|OwnerIndex=1063|IndexInSheet=285|OwnerPartId=-1|Location.X=700|Location.Y=820|Color=8388608|FontID=1|IsHidden=T|Text=Gold|Name=Contact Plating
|RECORD=41|OwnerIndex=1063|IndexInSheet=286|OwnerPartId=-1|Location.X=700|Location.Y=820|Color=8388608|FontID=1|IsHidden=T|Text=Copper Alloy|Name=Contact Material
|RECORD=41|OwnerIndex=1063|IndexInSheet=287|OwnerPartId=-1|Location.X=700|Location.Y=820|Color=8388608|FontID=1|IsHidden=T|Text=8.7mm|Name=Width
|RECORD=41|OwnerIndex=1063|IndexInSheet=288|OwnerPartId=-1|Location.X=700|Location.Y=820|Color=8388608|FontID=1|IsHidden=T|Text=2|Name=Number of Rows
|RECORD=41|OwnerIndex=1063|IndexInSheet=289|OwnerPartId=-1|Location.X=700|Location.Y=820|Color=8388608|FontID=1|IsHidden=T|Text=Black|Name=Color
|RECORD=41|OwnerIndex=1063|IndexInSheet=290|OwnerPartId=-1|Location.X=700|Location.Y=820|Color=8388608|FontID=1|IsHidden=T|Text=0.5mm|Name=Pitch
|RECORD=41|OwnerIndex=1063|IndexInSheet=291|OwnerPartId=-1|Location.X=700|Location.Y=820|Color=8388608|FontID=1|IsHidden=T|Text=Compliant|Name=ELV
|RECORD=41|OwnerIndex=1063|IndexInSheet=292|OwnerPartId=-1|Location.X=700|Location.Y=820|Color=8388608|FontID=1|IsHidden=T|Text=Black|Name=Housing Color
|RECORD=41|OwnerIndex=1063|IndexInSheet=293|OwnerPartId=-1|Location.X=700|Location.Y=820|Color=8388608|FontID=1|IsHidden=T|Text=50V|Name=Voltage Rating
|RECORD=41|OwnerIndex=1063|IndexInSheet=294|OwnerPartId=-1|Location.X=700|Location.Y=820|Color=8388608|FontID=1|IsHidden=T|Text=67|Name=Number of Positions
|RECORD=41|OwnerIndex=1063|IndexInSheet=295|OwnerPartId=-1|Location.X=700|Location.Y=820|Color=8388608|FontID=1|IsHidden=T|Text=Thermoplastic|Name=Housing Material
|RECORD=41|OwnerIndex=1063|IndexInSheet=296|OwnerPartId=-1|Location.X=700|Location.Y=820|Color=8388608|FontID=1|IsHidden=T|Text=Female|Name=Gender
|RECORD=41|OwnerIndex=1063|IndexInSheet=297|OwnerPartId=-1|Location.X=700|Location.Y=820|Color=8388608|FontID=1|IsHidden=T|Text=-40°C|Name=Min Operating Temperature
|RECORD=41|OwnerIndex=1063|IndexInSheet=298|OwnerPartId=-1|Location.X=700|Location.Y=820|Color=8388608|FontID=1|IsHidden=T|Text=80°C|Name=Max Operating Temperature
|RECORD=41|OwnerIndex=1063|IndexInSheet=299|OwnerPartId=-1|Location.X=700|Location.Y=820|Color=8388608|FontID=1|IsHidden=T|Text=500MR|Name=Insulation Resistance
|RECORD=41|OwnerIndex=1063|IndexInSheet=300|OwnerPartId=-1|Location.X=700|Location.Y=820|Color=8388608|FontID=1|IsHidden=T|Text=7.55mm|Name=Row Spacing
|RECORD=41|OwnerIndex=1063|IndexInSheet=301|OwnerPartId=-1|Location.X=700|Location.Y=820|Color=8388608|FontID=1|IsHidden=T|Text=Yes|Name=RoHS Compliant
|RECORD=41|OwnerIndex=1063|IndexInSheet=302|OwnerPartId=-1|Location.X=700|Location.Y=820|Color=8388608|FontID=1|IsHidden=T|Text=1200|Name=Package Quantity
|RECORD=41|OwnerIndex=1063|IndexInSheet=303|OwnerPartId=-1|Location.X=700|Location.Y=820|Color=8388608|FontID=1|IsHidden=T|Text=Tape and Reel|Name=Packaging
|RECORD=41|OwnerIndex=1063|IndexInSheet=304|OwnerPartId=-1|Location.X=700|Location.Y=820|Color=8388608|FontID=1|IsHidden=T|Text=3.2mm|Name=Height
|RECORD=41|OwnerIndex=1063|IndexInSheet=305|OwnerPartId=-1|Location.X=700|Location.Y=820|Color=8388608|FontID=1|IsHidden=T|Text=Solder|Name=Termination
|RECORD=41|OwnerIndex=1063|IndexInSheet=306|OwnerPartId=-1|Location.X=700|Location.Y=820|Color=8388608|FontID=1|IsHidden=T|Text=Thermoplastic|Name=Insulation Material
|RECORD=41|OwnerIndex=1063|IndexInSheet=307|OwnerPartId=-1|Location.X=700|Location.Y=820|Color=8388608|FontID=1|IsHidden=T|Text=50V|Name=Max Voltage Rating (AC)
|RECORD=41|OwnerIndex=1063|IndexInSheet=308|OwnerPartId=-1|Location.X=700|Location.Y=820|Color=8388608|FontID=1|IsHidden=T|Text=500mA|Name=Current Rating
|RECORD=34|OwnerIndex=1063|IndexInSheet=-1|OwnerPartId=-1|Location.X=700|Location.Y=820|Color=8388608|FontID=1|Text=J45|Name=Designator|ReadOnlyState=1
|RECORD=41|OwnerIndex=1063|IndexInSheet=-1|OwnerPartId=1|Location.X=700|Location.Y=90|Color=8388608|FontID=1|Text=2199119-3|Name=Comment
|RECORD=44|OwnerIndex=1063
|RECORD=45|OwnerIndex=1444|IndexInSheet=-1|UseComponentLibrary=T|ModelName=FP-2199119-3-MFG|ModelType=PCBLIB|DatafileCount=1|ModelDatafileEntity0=FP-2199119-3-MFG|ModelDatafileKind0=PCBLib|IsCurrent=T|DatalinksLocked=T|DatabaseDatalinksLocked=T
|RECORD=46|OwnerIndex=1445
|RECORD=48|OwnerIndex=1445
|RECORD=1|LibReference=a14843ccfa78e5d0b739856168502fb|ComponentDescription=CONN M.2 FEMALE 67POS 0.020 GOLD|PartCount=3|DisplayModeCount=1|IndexInSheet=104|OwnerPartId=-1|Location.X=1060|Location.Y=790|CurrentPartId=2|LibraryPath=*|SourceLibraryName=Altium Content Vault|TargetFileName=*|AreaColor=11599871|Color=128|PartIDLocked=T|DesignItemId=CMP-03365-000004-1|AllPinCount=69
|RECORD=14|OwnerIndex=1448|IsNotAccesible=T|OwnerPartId=1|Location.X=990|Location.Y=90|Corner.X=1040|Corner.Y=810|LineWidth=1|Color=128|AreaColor=11599871|IsSolid=T
|RECORD=8|OwnerIndex=1448|IsNotAccesible=T|IndexInSheet=1|OwnerPartId=1|Location.X=1015|Location.Y=790|Radius=3|SecondaryRadius=3|LineWidth=1|Color=16711680
|RECORD=13|OwnerIndex=1448|IsNotAccesible=T|IndexInSheet=2|OwnerPartId=1|Location.X=1018|Location.Y=790|Corner.X=1040|Corner.Y=790|LineWidth=1|Color=16711680
|RECORD=8|OwnerIndex=1448|IsNotAccesible=T|IndexInSheet=3|OwnerPartId=1|Location.X=1015|Location.Y=770|Radius=3|SecondaryRadius=3|LineWidth=1|Color=16711680
|RECORD=13|OwnerIndex=1448|IsNotAccesible=T|IndexInSheet=4|OwnerPartId=1|Location.X=1018|Location.Y=770|Corner.X=1040|Corner.Y=770|LineWidth=1|Color=16711680
|RECORD=8|OwnerIndex=1448|IsNotAccesible=T|IndexInSheet=5|OwnerPartId=1|Location.X=1015|Location.Y=750|Radius=3|SecondaryRadius=3|LineWidth=1|Color=16711680
|RECORD=13|OwnerIndex=1448|IsNotAccesible=T|IndexInSheet=6|OwnerPartId=1|Location.X=1018|Location.Y=750|Corner.X=1040|Corner.Y=750|LineWidth=1|Color=16711680
|RECORD=8|OwnerIndex=1448|IsNotAccesible=T|IndexInSheet=7|OwnerPartId=1|Location.X=1015|Location.Y=730|Radius=3|SecondaryRadius=3|LineWidth=1|Color=16711680
|RECORD=13|OwnerIndex=1448|IsNotAccesible=T|IndexInSheet=8|OwnerPartId=1|Location.X=1018|Location.Y=730|Corner.X=1040|Corner.Y=730|LineWidth=1|Color=16711680
|RECORD=8|OwnerIndex=1448|IsNotAccesible=T|IndexInSheet=9|OwnerPartId=1|Location.X=1015|Location.Y=710|Radius=3|SecondaryRadius=3|LineWidth=1|Color=16711680
|RECORD=13|OwnerIndex=1448|IsNotAccesible=T|IndexInSheet=10|OwnerPartId=1|Location.X=1018|Location.Y=710|Corner.X=1040|Corner.Y=710|LineWidth=1|Color=16711680
|RECORD=8|OwnerIndex=1448|IsNotAccesible=T|IndexInSheet=11|OwnerPartId=1|Location.X=1015|Location.Y=690|Radius=3|SecondaryRadius=3|LineWidth=1|Color=16711680
|RECORD=13|OwnerIndex=1448|IsNotAccesible=T|IndexInSheet=12|OwnerPartId=1|Location.X=1018|Location.Y=690|Corner.X=1040|Corner.Y=690|LineWidth=1|Color=16711680
|RECORD=8|OwnerIndex=1448|IsNotAccesible=T|IndexInSheet=13|OwnerPartId=1|Location.X=1015|Location.Y=670|Radius=3|SecondaryRadius=3|LineWidth=1|Color=16711680
|RECORD=13|OwnerIndex=1448|IsNotAccesible=T|IndexInSheet=14|OwnerPartId=1|Location.X=1018|Location.Y=670|Corner.X=1040|Corner.Y=670|LineWidth=1|Color=16711680
|RECORD=8|OwnerIndex=1448|IsNotAccesible=T|IndexInSheet=15|OwnerPartId=1|Location.X=1015|Location.Y=650|Radius=3|SecondaryRadius=3|LineWidth=1|Color=16711680
|RECORD=13|OwnerIndex=1448|IsNotAccesible=T|IndexInSheet=16|OwnerPartId=1|Location.X=1018|Location.Y=650|Corner.X=1040|Corner.Y=650|LineWidth=1|Color=16711680
|RECORD=8|OwnerIndex=1448|IsNotAccesible=T|IndexInSheet=17|OwnerPartId=1|Location.X=1015|Location.Y=630|Radius=3|SecondaryRadius=3|LineWidth=1|Color=16711680
|RECORD=13|OwnerIndex=1448|IsNotAccesible=T|IndexInSheet=18|OwnerPartId=1|Location.X=1018|Location.Y=630|Corner.X=1040|Corner.Y=630|LineWidth=1|Color=16711680
|RECORD=8|OwnerIndex=1448|IsNotAccesible=T|IndexInSheet=19|OwnerPartId=1|Location.X=1015|Location.Y=610|Radius=3|SecondaryRadius=3|LineWidth=1|Color=16711680
|RECORD=13|OwnerIndex=1448|IsNotAccesible=T|IndexInSheet=20|OwnerPartId=1|Location.X=1018|Location.Y=610|Corner.X=1040|Corner.Y=610|LineWidth=1|Color=16711680
|RECORD=8|OwnerIndex=1448|IsNotAccesible=T|IndexInSheet=21|OwnerPartId=1|Location.X=1015|Location.Y=590|Radius=3|SecondaryRadius=3|LineWidth=1|Color=16711680
|RECORD=13|OwnerIndex=1448|IsNotAccesible=T|IndexInSheet=22|OwnerPartId=1|Location.X=1018|Location.Y=590|Corner.X=1040|Corner.Y=590|LineWidth=1|Color=16711680
|RECORD=8|OwnerIndex=1448|IsNotAccesible=T|IndexInSheet=23|OwnerPartId=1|Location.X=1015|Location.Y=570|Radius=3|SecondaryRadius=3|LineWidth=1|Color=16711680
|RECORD=13|OwnerIndex=1448|IsNotAccesible=T|IndexInSheet=24|OwnerPartId=1|Location.X=1018|Location.Y=570|Corner.X=1040|Corner.Y=570|LineWidth=1|Color=16711680
|RECORD=8|OwnerIndex=1448|IsNotAccesible=T|IndexInSheet=25|OwnerPartId=1|Location.X=1015|Location.Y=550|Radius=3|SecondaryRadius=3|LineWidth=1|Color=16711680
|RECORD=13|OwnerIndex=1448|IsNotAccesible=T|IndexInSheet=26|OwnerPartId=1|Location.X=1018|Location.Y=550|Corner.X=1040|Corner.Y=550|LineWidth=1|Color=16711680
|RECORD=8|OwnerIndex=1448|IsNotAccesible=T|IndexInSheet=27|OwnerPartId=1|Location.X=1015|Location.Y=530|Radius=3|SecondaryRadius=3|LineWidth=1|Color=16711680
|RECORD=13|OwnerIndex=1448|IsNotAccesible=T|IndexInSheet=28|OwnerPartId=1|Location.X=1018|Location.Y=530|Corner.X=1040|Corner.Y=530|LineWidth=1|Color=16711680
|RECORD=8|OwnerIndex=1448|IsNotAccesible=T|IndexInSheet=29|OwnerPartId=1|Location.X=1015|Location.Y=510|Radius=3|SecondaryRadius=3|LineWidth=1|Color=16711680
|RECORD=13|OwnerIndex=1448|IsNotAccesible=T|IndexInSheet=30|OwnerPartId=1|Location.X=1018|Location.Y=510|Corner.X=1040|Corner.Y=510|LineWidth=1|Color=16711680
|RECORD=8|OwnerIndex=1448|IsNotAccesible=T|IndexInSheet=31|OwnerPartId=1|Location.X=1015|Location.Y=490|Radius=3|SecondaryRadius=3|LineWidth=1|Color=16711680
|RECORD=13|OwnerIndex=1448|IsNotAccesible=T|IndexInSheet=32|OwnerPartId=1|Location.X=1018|Location.Y=490|Corner.X=1040|Corner.Y=490|LineWidth=1|Color=16711680
|RECORD=8|OwnerIndex=1448|IsNotAccesible=T|IndexInSheet=33|OwnerPartId=1|Location.X=1015|Location.Y=470|Radius=3|SecondaryRadius=3|LineWidth=1|Color=16711680
|RECORD=13|OwnerIndex=1448|IsNotAccesible=T|IndexInSheet=34|OwnerPartId=1|Location.X=1018|Location.Y=470|Corner.X=1040|Corner.Y=470|LineWidth=1|Color=16711680
|RECORD=8|OwnerIndex=1448|IsNotAccesible=T|IndexInSheet=35|OwnerPartId=1|Location.X=1015|Location.Y=450|Radius=3|SecondaryRadius=3|LineWidth=1|Color=16711680
|RECORD=13|OwnerIndex=1448|IsNotAccesible=T|IndexInSheet=36|OwnerPartId=1|Location.X=1018|Location.Y=450|Corner.X=1040|Corner.Y=450|LineWidth=1|Color=16711680
|RECORD=8|OwnerIndex=1448|IsNotAccesible=T|IndexInSheet=37|OwnerPartId=1|Location.X=1015|Location.Y=430|Radius=3|SecondaryRadius=3|LineWidth=1|Color=16711680
|RECORD=13|OwnerIndex=1448|IsNotAccesible=T|IndexInSheet=38|OwnerPartId=1|Location.X=1018|Location.Y=430|Corner.X=1040|Corner.Y=430|LineWidth=1|Color=16711680
|RECORD=8|OwnerIndex=1448|IsNotAccesible=T|IndexInSheet=39|OwnerPartId=1|Location.X=1015|Location.Y=410|Radius=3|SecondaryRadius=3|LineWidth=1|Color=16711680
|RECORD=13|OwnerIndex=1448|IsNotAccesible=T|IndexInSheet=40|OwnerPartId=1|Location.X=1018|Location.Y=410|Corner.X=1040|Corner.Y=410|LineWidth=1|Color=16711680
|RECORD=8|OwnerIndex=1448|IsNotAccesible=T|IndexInSheet=41|OwnerPartId=1|Location.X=1015|Location.Y=390|Radius=3|SecondaryRadius=3|LineWidth=1|Color=16711680
|RECORD=13|OwnerIndex=1448|IsNotAccesible=T|IndexInSheet=42|OwnerPartId=1|Location.X=1018|Location.Y=390|Corner.X=1040|Corner.Y=390|LineWidth=1|Color=16711680
|RECORD=8|OwnerIndex=1448|IsNotAccesible=T|IndexInSheet=43|OwnerPartId=1|Location.X=1015|Location.Y=370|Radius=3|SecondaryRadius=3|LineWidth=1|Color=16711680
|RECORD=13|OwnerIndex=1448|IsNotAccesible=T|IndexInSheet=44|OwnerPartId=1|Location.X=1018|Location.Y=370|Corner.X=1040|Corner.Y=370|LineWidth=1|Color=16711680
|RECORD=8|OwnerIndex=1448|IsNotAccesible=T|IndexInSheet=45|OwnerPartId=1|Location.X=1015|Location.Y=350|Radius=3|SecondaryRadius=3|LineWidth=1|Color=16711680
|RECORD=13|OwnerIndex=1448|IsNotAccesible=T|IndexInSheet=46|OwnerPartId=1|Location.X=1018|Location.Y=350|Corner.X=1040|Corner.Y=350|LineWidth=1|Color=16711680
|RECORD=8|OwnerIndex=1448|IsNotAccesible=T|IndexInSheet=47|OwnerPartId=1|Location.X=1015|Location.Y=330|Radius=3|SecondaryRadius=3|LineWidth=1|Color=16711680
|RECORD=13|OwnerIndex=1448|IsNotAccesible=T|IndexInSheet=48|OwnerPartId=1|Location.X=1018|Location.Y=330|Corner.X=1040|Corner.Y=330|LineWidth=1|Color=16711680
|RECORD=8|OwnerIndex=1448|IsNotAccesible=T|IndexInSheet=49|OwnerPartId=1|Location.X=1015|Location.Y=310|Radius=3|SecondaryRadius=3|LineWidth=1|Color=16711680
|RECORD=13|OwnerIndex=1448|IsNotAccesible=T|IndexInSheet=50|OwnerPartId=1|Location.X=1018|Location.Y=310|Corner.X=1040|Corner.Y=310|LineWidth=1|Color=16711680
|RECORD=8|OwnerIndex=1448|IsNotAccesible=T|IndexInSheet=51|OwnerPartId=1|Location.X=1015|Location.Y=290|Radius=3|SecondaryRadius=3|LineWidth=1|Color=16711680
|RECORD=13|OwnerIndex=1448|IsNotAccesible=T|IndexInSheet=52|OwnerPartId=1|Location.X=1018|Location.Y=290|Corner.X=1040|Corner.Y=290|LineWidth=1|Color=16711680
|RECORD=8|OwnerIndex=1448|IsNotAccesible=T|IndexInSheet=53|OwnerPartId=1|Location.X=1015|Location.Y=270|Radius=3|SecondaryRadius=3|LineWidth=1|Color=16711680
|RECORD=13|OwnerIndex=1448|IsNotAccesible=T|IndexInSheet=54|OwnerPartId=1|Location.X=1018|Location.Y=270|Corner.X=1040|Corner.Y=270|LineWidth=1|Color=16711680
|RECORD=8|OwnerIndex=1448|IsNotAccesible=T|IndexInSheet=55|OwnerPartId=1|Location.X=1015|Location.Y=250|Radius=3|SecondaryRadius=3|LineWidth=1|Color=16711680
|RECORD=13|OwnerIndex=1448|IsNotAccesible=T|IndexInSheet=56|OwnerPartId=1|Location.X=1018|Location.Y=250|Corner.X=1040|Corner.Y=250|LineWidth=1|Color=16711680
|RECORD=8|OwnerIndex=1448|IsNotAccesible=T|IndexInSheet=57|OwnerPartId=1|Location.X=1015|Location.Y=230|Radius=3|SecondaryRadius=3|LineWidth=1|Color=16711680
|RECORD=13|OwnerIndex=1448|IsNotAccesible=T|IndexInSheet=58|OwnerPartId=1|Location.X=1018|Location.Y=230|Corner.X=1040|Corner.Y=230|LineWidth=1|Color=16711680
|RECORD=8|OwnerIndex=1448|IsNotAccesible=T|IndexInSheet=59|OwnerPartId=1|Location.X=1015|Location.Y=210|Radius=3|SecondaryRadius=3|LineWidth=1|Color=16711680
|RECORD=13|OwnerIndex=1448|IsNotAccesible=T|IndexInSheet=60|OwnerPartId=1|Location.X=1018|Location.Y=210|Corner.X=1040|Corner.Y=210|LineWidth=1|Color=16711680
|RECORD=8|OwnerIndex=1448|IsNotAccesible=T|IndexInSheet=61|OwnerPartId=1|Location.X=1015|Location.Y=190|Radius=3|SecondaryRadius=3|LineWidth=1|Color=16711680
|RECORD=13|OwnerIndex=1448|IsNotAccesible=T|IndexInSheet=62|OwnerPartId=1|Location.X=1018|Location.Y=190|Corner.X=1040|Corner.Y=190|LineWidth=1|Color=16711680
|RECORD=8|OwnerIndex=1448|IsNotAccesible=T|IndexInSheet=63|OwnerPartId=1|Location.X=1015|Location.Y=170|Radius=3|SecondaryRadius=3|LineWidth=1|Color=16711680
|RECORD=13|OwnerIndex=1448|IsNotAccesible=T|IndexInSheet=64|OwnerPartId=1|Location.X=1018|Location.Y=170|Corner.X=1040|Corner.Y=170|LineWidth=1|Color=16711680
|RECORD=8|OwnerIndex=1448|IsNotAccesible=T|IndexInSheet=65|OwnerPartId=1|Location.X=1015|Location.Y=150|Radius=3|SecondaryRadius=3|LineWidth=1|Color=16711680
|RECORD=13|OwnerIndex=1448|IsNotAccesible=T|IndexInSheet=66|OwnerPartId=1|Location.X=1018|Location.Y=150|Corner.X=1040|Corner.Y=150|LineWidth=1|Color=16711680
|RECORD=8|OwnerIndex=1448|IsNotAccesible=T|IndexInSheet=67|OwnerPartId=1|Location.X=1015|Location.Y=130|Radius=3|SecondaryRadius=3|LineWidth=1|Color=16711680
|RECORD=13|OwnerIndex=1448|IsNotAccesible=T|IndexInSheet=68|OwnerPartId=1|Location.X=1018|Location.Y=130|Corner.X=1040|Corner.Y=130|LineWidth=1|Color=16711680
|RECORD=8|OwnerIndex=1448|IsNotAccesible=T|IndexInSheet=69|OwnerPartId=1|Location.X=1015|Location.Y=110|Radius=3|SecondaryRadius=3|LineWidth=1|Color=16711680
|RECORD=13|OwnerIndex=1448|IsNotAccesible=T|IndexInSheet=70|OwnerPartId=1|Location.X=1018|Location.Y=110|Corner.X=1040|Corner.Y=110|LineWidth=1|Color=16711680
|RECORD=4|OwnerIndex=1448|IsNotAccesible=T|IndexInSheet=71|OwnerPartId=1|Location.X=1033|Location.Y=802|Justification=8|Color=8388608|FontID=1|Text=1
|RECORD=4|OwnerIndex=1448|IsNotAccesible=T|IndexInSheet=72|OwnerPartId=1|Location.X=1033|Location.Y=782|Justification=8|Color=8388608|FontID=1|Text=3
|RECORD=4|OwnerIndex=1448|IsNotAccesible=T|IndexInSheet=73|OwnerPartId=1|Location.X=1033|Location.Y=762|Justification=8|Color=8388608|FontID=1|Text=5
|RECORD=4|OwnerIndex=1448|IsNotAccesible=T|IndexInSheet=74|OwnerPartId=1|Location.X=1033|Location.Y=742|Justification=8|Color=8388608|FontID=1|Text=7
|RECORD=4|OwnerIndex=1448|IsNotAccesible=T|IndexInSheet=75|OwnerPartId=1|Location.X=1033|Location.Y=722|Justification=8|Color=8388608|FontID=1|Text=9
|RECORD=4|OwnerIndex=1448|IsNotAccesible=T|IndexInSheet=76|OwnerPartId=1|Location.X=1033|Location.Y=702|Justification=8|Color=8388608|FontID=1|Text=11
|RECORD=4|OwnerIndex=1448|IsNotAccesible=T|IndexInSheet=77|OwnerPartId=1|Location.X=1033|Location.Y=682|Justification=8|Color=8388608|FontID=1|Text=21
|RECORD=4|OwnerIndex=1448|IsNotAccesible=T|IndexInSheet=78|OwnerPartId=1|Location.X=1033|Location.Y=662|Justification=8|Color=8388608|FontID=1|Text=23
|RECORD=4|OwnerIndex=1448|IsNotAccesible=T|IndexInSheet=79|OwnerPartId=1|Location.X=1033|Location.Y=642|Justification=8|Color=8388608|FontID=1|Text=25
|RECORD=4|OwnerIndex=1448|IsNotAccesible=T|IndexInSheet=80|OwnerPartId=1|Location.X=1033|Location.Y=622|Justification=8|Color=8388608|FontID=1|Text=27
|RECORD=4|OwnerIndex=1448|IsNotAccesible=T|IndexInSheet=81|OwnerPartId=1|Location.X=1033|Location.Y=602|Justification=8|Color=8388608|FontID=1|Text=29
|RECORD=4|OwnerIndex=1448|IsNotAccesible=T|IndexInSheet=82|OwnerPartId=1|Location.X=1033|Location.Y=582|Justification=8|Color=8388608|FontID=1|Text=31
|RECORD=4|OwnerIndex=1448|IsNotAccesible=T|IndexInSheet=83|OwnerPartId=1|Location.X=1033|Location.Y=562|Justification=8|Color=8388608|FontID=1|Text=33
|RECORD=4|OwnerIndex=1448|IsNotAccesible=T|IndexInSheet=84|OwnerPartId=1|Location.X=1033|Location.Y=542|Justification=8|Color=8388608|FontID=1|Text=35
|RECORD=4|OwnerIndex=1448|IsNotAccesible=T|IndexInSheet=85|OwnerPartId=1|Location.X=1033|Location.Y=522|Justification=8|Color=8388608|FontID=1|Text=37
|RECORD=4|OwnerIndex=1448|IsNotAccesible=T|IndexInSheet=86|OwnerPartId=1|Location.X=1033|Location.Y=502|Justification=8|Color=8388608|FontID=1|Text=39
|RECORD=4|OwnerIndex=1448|IsNotAccesible=T|IndexInSheet=87|OwnerPartId=1|Location.X=1033|Location.Y=482|Justification=8|Color=8388608|FontID=1|Text=41
|RECORD=4|OwnerIndex=1448|IsNotAccesible=T|IndexInSheet=88|OwnerPartId=1|Location.X=1033|Location.Y=462|Justification=8|Color=8388608|FontID=1|Text=43
|RECORD=4|OwnerIndex=1448|IsNotAccesible=T|IndexInSheet=89|OwnerPartId=1|Location.X=1033|Location.Y=442|Justification=8|Color=8388608|FontID=1|Text=45
|RECORD=4|OwnerIndex=1448|IsNotAccesible=T|IndexInSheet=90|OwnerPartId=1|Location.X=1033|Location.Y=422|Justification=8|Color=8388608|FontID=1|Text=47
|RECORD=4|OwnerIndex=1448|IsNotAccesible=T|IndexInSheet=91|OwnerPartId=1|Location.X=1033|Location.Y=402|Justification=8|Color=8388608|FontID=1|Text=49
|RECORD=4|OwnerIndex=1448|IsNotAccesible=T|IndexInSheet=92|OwnerPartId=1|Location.X=1033|Location.Y=382|Justification=8|Color=8388608|FontID=1|Text=51
|RECORD=4|OwnerIndex=1448|IsNotAccesible=T|IndexInSheet=93|OwnerPartId=1|Location.X=1033|Location.Y=362|Justification=8|Color=8388608|FontID=1|Text=53
|RECORD=4|OwnerIndex=1448|IsNotAccesible=T|IndexInSheet=94|OwnerPartId=1|Location.X=1033|Location.Y=342|Justification=8|Color=8388608|FontID=1|Text=55
|RECORD=4|OwnerIndex=1448|IsNotAccesible=T|IndexInSheet=95|OwnerPartId=1|Location.X=1033|Location.Y=322|Justification=8|Color=8388608|FontID=1|Text=57
|RECORD=4|OwnerIndex=1448|IsNotAccesible=T|IndexInSheet=96|OwnerPartId=1|Location.X=1033|Location.Y=302|Justification=8|Color=8388608|FontID=1|Text=59
|RECORD=4|OwnerIndex=1448|IsNotAccesible=T|IndexInSheet=97|OwnerPartId=1|Location.X=1033|Location.Y=282|Justification=8|Color=8388608|FontID=1|Text=61
|RECORD=4|OwnerIndex=1448|IsNotAccesible=T|IndexInSheet=98|OwnerPartId=1|Location.X=1033|Location.Y=262|Justification=8|Color=8388608|FontID=1|Text=63
|RECORD=4|OwnerIndex=1448|IsNotAccesible=T|IndexInSheet=99|OwnerPartId=1|Location.X=1033|Location.Y=242|Justification=8|Color=8388608|FontID=1|Text=65
|RECORD=4|OwnerIndex=1448|IsNotAccesible=T|IndexInSheet=100|OwnerPartId=1|Location.X=1033|Location.Y=222|Justification=8|Color=8388608|FontID=1|Text=67
|RECORD=4|OwnerIndex=1448|IsNotAccesible=T|IndexInSheet=101|OwnerPartId=1|Location.X=1033|Location.Y=202|Justification=8|Color=8388608|FontID=1|Text=69
|RECORD=4|OwnerIndex=1448|IsNotAccesible=T|IndexInSheet=102|OwnerPartId=1|Location.X=1033|Location.Y=182|Justification=8|Color=8388608|FontID=1|Text=71
|RECORD=4|OwnerIndex=1448|IsNotAccesible=T|IndexInSheet=103|OwnerPartId=1|Location.X=1033|Location.Y=162|Justification=8|Color=8388608|FontID=1|Text=73
|RECORD=4|OwnerIndex=1448|IsNotAccesible=T|IndexInSheet=104|OwnerPartId=1|Location.X=1033|Location.Y=142|Justification=8|Color=8388608|FontID=1|Text=75
|RECORD=4|OwnerIndex=1448|IsNotAccesible=T|IndexInSheet=105|OwnerPartId=1|Location.X=1033|Location.Y=122|Justification=8|Color=8388608|FontID=1|Text=MNT 2
|RECORD=2|OwnerIndex=1448|OwnerPartId=1|Electrical=4|PinConglomerate=48|PinLength=20|Location.X=1040|Location.Y=790|Name=1|Designator=1|PinName_PositionConglomerate=16|Name_CustomFontID=1|PinDesignator_PositionConglomerate=16|Designator_CustomFontID=1|PinPropagationDelay=0.000000E+000
|RECORD=2|OwnerIndex=1448|OwnerPartId=1|Electrical=4|PinConglomerate=48|PinLength=20|Location.X=1040|Location.Y=770|Name=3|Designator=3|PinName_PositionConglomerate=16|Name_CustomFontID=1|PinDesignator_PositionConglomerate=16|Designator_CustomFontID=1|PinPropagationDelay=0.000000E+000
|RECORD=2|OwnerIndex=1448|OwnerPartId=1|Electrical=4|PinConglomerate=48|PinLength=20|Location.X=1040|Location.Y=750|Name=5|Designator=5|PinName_PositionConglomerate=16|Name_CustomFontID=1|PinDesignator_PositionConglomerate=16|Designator_CustomFontID=1|PinPropagationDelay=0.000000E+000
|RECORD=2|OwnerIndex=1448|OwnerPartId=1|Electrical=4|PinConglomerate=48|PinLength=20|Location.X=1040|Location.Y=730|Name=7|Designator=7|PinName_PositionConglomerate=16|Name_CustomFontID=1|PinDesignator_PositionConglomerate=16|Designator_CustomFontID=1|PinPropagationDelay=0.000000E+000
|RECORD=2|OwnerIndex=1448|OwnerPartId=1|Electrical=4|PinConglomerate=48|PinLength=20|Location.X=1040|Location.Y=710|Name=9|Designator=9|PinName_PositionConglomerate=16|Name_CustomFontID=1|PinDesignator_PositionConglomerate=16|Designator_CustomFontID=1|PinPropagationDelay=0.000000E+000
|RECORD=2|OwnerIndex=1448|OwnerPartId=1|Electrical=4|PinConglomerate=48|PinLength=20|Location.X=1040|Location.Y=690|Name=11|Designator=11|PinName_PositionConglomerate=16|Name_CustomFontID=1|PinDesignator_PositionConglomerate=16|Designator_CustomFontID=1|PinPropagationDelay=0.000000E+000
|RECORD=2|OwnerIndex=1448|OwnerPartId=1|Electrical=4|PinConglomerate=48|PinLength=20|Location.X=1040|Location.Y=670|Name=21|Designator=21|PinName_PositionConglomerate=16|Name_CustomFontID=1|PinDesignator_PositionConglomerate=16|Designator_CustomFontID=1|PinPropagationDelay=0.000000E+000
|RECORD=2|OwnerIndex=1448|OwnerPartId=1|Electrical=4|PinConglomerate=48|PinLength=20|Location.X=1040|Location.Y=650|Name=23|Designator=23|PinName_PositionConglomerate=16|Name_CustomFontID=1|PinDesignator_PositionConglomerate=16|Designator_CustomFontID=1|PinPropagationDelay=0.000000E+000
|RECORD=2|OwnerIndex=1448|OwnerPartId=1|Electrical=4|PinConglomerate=48|PinLength=20|Location.X=1040|Location.Y=630|Name=25|Designator=25|PinName_PositionConglomerate=16|Name_CustomFontID=1|PinDesignator_PositionConglomerate=16|Designator_CustomFontID=1|PinPropagationDelay=0.000000E+000
|RECORD=2|OwnerIndex=1448|OwnerPartId=1|Electrical=4|PinConglomerate=48|PinLength=20|Location.X=1040|Location.Y=610|Name=27|Designator=27|PinName_PositionConglomerate=16|Name_CustomFontID=1|PinDesignator_PositionConglomerate=16|Designator_CustomFontID=1|PinPropagationDelay=0.000000E+000
|RECORD=2|OwnerIndex=1448|OwnerPartId=1|Electrical=4|PinConglomerate=48|PinLength=20|Location.X=1040|Location.Y=590|Name=29|Designator=29|PinName_PositionConglomerate=16|Name_CustomFontID=1|PinDesignator_PositionConglomerate=16|Designator_CustomFontID=1|PinPropagationDelay=0.000000E+000
|RECORD=2|OwnerIndex=1448|OwnerPartId=1|Electrical=4|PinConglomerate=48|PinLength=20|Location.X=1040|Location.Y=570|Name=31|Designator=31|PinName_PositionConglomerate=16|Name_CustomFontID=1|PinDesignator_PositionConglomerate=16|Designator_CustomFontID=1|PinPropagationDelay=0.000000E+000
|RECORD=2|OwnerIndex=1448|OwnerPartId=1|Electrical=4|PinConglomerate=48|PinLength=20|Location.X=1040|Location.Y=550|Name=33|Designator=33|PinName_PositionConglomerate=16|Name_CustomFontID=1|PinDesignator_PositionConglomerate=16|Designator_CustomFontID=1|PinPropagationDelay=0.000000E+000
|RECORD=2|OwnerIndex=1448|OwnerPartId=1|Electrical=4|PinConglomerate=48|PinLength=20|Location.X=1040|Location.Y=530|Name=35|Designator=35|PinName_PositionConglomerate=16|Name_CustomFontID=1|PinDesignator_PositionConglomerate=16|Designator_CustomFontID=1|PinPropagationDelay=0.000000E+000
|RECORD=2|OwnerIndex=1448|OwnerPartId=1|Electrical=4|PinConglomerate=48|PinLength=20|Location.X=1040|Location.Y=510|Name=37|Designator=37|PinName_PositionConglomerate=16|Name_CustomFontID=1|PinDesignator_PositionConglomerate=16|Designator_CustomFontID=1|PinPropagationDelay=0.000000E+000
|RECORD=2|OwnerIndex=1448|OwnerPartId=1|Electrical=4|PinConglomerate=48|PinLength=20|Location.X=1040|Location.Y=490|Name=39|Designator=39|PinName_PositionConglomerate=16|Name_CustomFontID=1|PinDesignator_PositionConglomerate=16|Designator_CustomFontID=1|PinPropagationDelay=0.000000E+000
|RECORD=2|OwnerIndex=1448|OwnerPartId=1|Electrical=4|PinConglomerate=48|PinLength=20|Location.X=1040|Location.Y=470|Name=41|Designator=41|PinName_PositionConglomerate=16|Name_CustomFontID=1|PinDesignator_PositionConglomerate=16|Designator_CustomFontID=1|PinPropagationDelay=0.000000E+000
|RECORD=2|OwnerIndex=1448|OwnerPartId=1|Electrical=4|PinConglomerate=48|PinLength=20|Location.X=1040|Location.Y=450|Name=43|Designator=43|PinName_PositionConglomerate=16|Name_CustomFontID=1|PinDesignator_PositionConglomerate=16|Designator_CustomFontID=1|PinPropagationDelay=0.000000E+000
|RECORD=2|OwnerIndex=1448|OwnerPartId=1|Electrical=4|PinConglomerate=48|PinLength=20|Location.X=1040|Location.Y=430|Name=45|Designator=45|PinName_PositionConglomerate=16|Name_CustomFontID=1|PinDesignator_PositionConglomerate=16|Designator_CustomFontID=1|PinPropagationDelay=0.000000E+000
|RECORD=2|OwnerIndex=1448|OwnerPartId=1|Electrical=4|PinConglomerate=48|PinLength=20|Location.X=1040|Location.Y=410|Name=47|Designator=47|PinName_PositionConglomerate=16|Name_CustomFontID=1|PinDesignator_PositionConglomerate=16|Designator_CustomFontID=1|PinPropagationDelay=0.000000E+000
|RECORD=2|OwnerIndex=1448|OwnerPartId=1|Electrical=4|PinConglomerate=48|PinLength=20|Location.X=1040|Location.Y=390|Name=49|Designator=49|PinName_PositionConglomerate=16|Name_CustomFontID=1|PinDesignator_PositionConglomerate=16|Designator_CustomFontID=1|PinPropagationDelay=0.000000E+000
|RECORD=2|OwnerIndex=1448|OwnerPartId=1|Electrical=4|PinConglomerate=48|PinLength=20|Location.X=1040|Location.Y=370|Name=51|Designator=51|PinName_PositionConglomerate=16|Name_CustomFontID=1|PinDesignator_PositionConglomerate=16|Designator_CustomFontID=1|PinPropagationDelay=0.000000E+000
|RECORD=2|OwnerIndex=1448|OwnerPartId=1|Electrical=4|PinConglomerate=48|PinLength=20|Location.X=1040|Location.Y=350|Name=53|Designator=53|PinName_PositionConglomerate=16|Name_CustomFontID=1|PinDesignator_PositionConglomerate=16|Designator_CustomFontID=1|PinPropagationDelay=0.000000E+000
|RECORD=2|OwnerIndex=1448|OwnerPartId=1|Electrical=4|PinConglomerate=48|PinLength=20|Location.X=1040|Location.Y=330|Name=55|Designator=55|PinName_PositionConglomerate=16|Name_CustomFontID=1|PinDesignator_PositionConglomerate=16|Designator_CustomFontID=1|PinPropagationDelay=0.000000E+000
|RECORD=2|OwnerIndex=1448|OwnerPartId=1|Electrical=4|PinConglomerate=48|PinLength=20|Location.X=1040|Location.Y=310|Name=57|Designator=57|PinName_PositionConglomerate=16|Name_CustomFontID=1|PinDesignator_PositionConglomerate=16|Designator_CustomFontID=1|PinPropagationDelay=0.000000E+000
|RECORD=2|OwnerIndex=1448|OwnerPartId=1|Electrical=4|PinConglomerate=48|PinLength=20|Location.X=1040|Location.Y=290|Name=59|Designator=59|PinName_PositionConglomerate=16|Name_CustomFontID=1|PinDesignator_PositionConglomerate=16|Designator_CustomFontID=1|PinPropagationDelay=0.000000E+000
|RECORD=2|OwnerIndex=1448|OwnerPartId=1|Electrical=4|PinConglomerate=48|PinLength=20|Location.X=1040|Location.Y=270|Name=61|Designator=61|PinName_PositionConglomerate=16|Name_CustomFontID=1|PinDesignator_PositionConglomerate=16|Designator_CustomFontID=1|PinPropagationDelay=0.000000E+000
|RECORD=2|OwnerIndex=1448|OwnerPartId=1|Electrical=4|PinConglomerate=48|PinLength=20|Location.X=1040|Location.Y=250|Name=63|Designator=63|PinName_PositionConglomerate=16|Name_CustomFontID=1|PinDesignator_PositionConglomerate=16|Designator_CustomFontID=1|PinPropagationDelay=0.000000E+000
|RECORD=2|OwnerIndex=1448|OwnerPartId=1|Electrical=4|PinConglomerate=48|PinLength=20|Location.X=1040|Location.Y=230|Name=65|Designator=65|PinName_PositionConglomerate=16|Name_CustomFontID=1|PinDesignator_PositionConglomerate=16|Designator_CustomFontID=1|PinPropagationDelay=0.000000E+000
|RECORD=2|OwnerIndex=1448|OwnerPartId=1|Electrical=4|PinConglomerate=48|PinLength=20|Location.X=1040|Location.Y=210|Name=67|Designator=67|PinName_PositionConglomerate=16|Name_CustomFontID=1|PinDesignator_PositionConglomerate=16|Designator_CustomFontID=1|PinPropagationDelay=0.000000E+000
|RECORD=2|OwnerIndex=1448|OwnerPartId=1|Electrical=4|PinConglomerate=48|PinLength=20|Location.X=1040|Location.Y=190|Name=69|Designator=69|PinName_PositionConglomerate=16|Name_CustomFontID=1|PinDesignator_PositionConglomerate=16|Designator_CustomFontID=1|PinPropagationDelay=0.000000E+000
|RECORD=2|OwnerIndex=1448|OwnerPartId=1|Electrical=4|PinConglomerate=48|PinLength=20|Location.X=1040|Location.Y=170|Name=71|Designator=71|PinName_PositionConglomerate=16|Name_CustomFontID=1|PinDesignator_PositionConglomerate=16|Designator_CustomFontID=1|PinPropagationDelay=0.000000E+000
|RECORD=2|OwnerIndex=1448|OwnerPartId=1|Electrical=4|PinConglomerate=48|PinLength=20|Location.X=1040|Location.Y=150|Name=73|Designator=73|PinName_PositionConglomerate=16|Name_CustomFontID=1|PinDesignator_PositionConglomerate=16|Designator_CustomFontID=1|PinPropagationDelay=0.000000E+000
|RECORD=2|OwnerIndex=1448|OwnerPartId=1|Electrical=4|PinConglomerate=48|PinLength=20|Location.X=1040|Location.Y=130|Name=75|Designator=75|PinName_PositionConglomerate=16|Name_CustomFontID=1|PinDesignator_PositionConglomerate=16|Designator_CustomFontID=1|PinPropagationDelay=0.000000E+000
|RECORD=2|OwnerIndex=1448|OwnerPartId=1|Electrical=4|PinConglomerate=48|PinLength=20|Location.X=1040|Location.Y=110|Name=MNT 2|Designator=77|PinName_PositionConglomerate=16|Name_CustomFontID=1|PinDesignator_PositionConglomerate=16|Designator_CustomFontID=1|PinPropagationDelay=0.000000E+000
|RECORD=14|OwnerIndex=1448|IsNotAccesible=T|IndexInSheet=141|OwnerPartId=2|Location.X=990|Location.Y=110|Corner.X=1040|Corner.Y=810|LineWidth=1|Color=128|AreaColor=11599871|IsSolid=T
|RECORD=8|OwnerIndex=1448|IsNotAccesible=T|IndexInSheet=142|OwnerPartId=2|Location.X=1015|Location.Y=790|Radius=3|SecondaryRadius=3|LineWidth=1|Color=16711680
|RECORD=13|OwnerIndex=1448|IsNotAccesible=T|IndexInSheet=143|OwnerPartId=2|Location.X=1018|Location.Y=790|Corner.X=1040|Corner.Y=790|LineWidth=1|Color=16711680
|RECORD=8|OwnerIndex=1448|IsNotAccesible=T|IndexInSheet=144|OwnerPartId=2|Location.X=1015|Location.Y=770|Radius=3|SecondaryRadius=3|LineWidth=1|Color=16711680
|RECORD=13|OwnerIndex=1448|IsNotAccesible=T|IndexInSheet=145|OwnerPartId=2|Location.X=1018|Location.Y=770|Corner.X=1040|Corner.Y=770|LineWidth=1|Color=16711680
|RECORD=8|OwnerIndex=1448|IsNotAccesible=T|IndexInSheet=146|OwnerPartId=2|Location.X=1015|Location.Y=750|Radius=3|SecondaryRadius=3|LineWidth=1|Color=16711680
|RECORD=13|OwnerIndex=1448|IsNotAccesible=T|IndexInSheet=147|OwnerPartId=2|Location.X=1018|Location.Y=750|Corner.X=1040|Corner.Y=750|LineWidth=1|Color=16711680
|RECORD=8|OwnerIndex=1448|IsNotAccesible=T|IndexInSheet=148|OwnerPartId=2|Location.X=1015|Location.Y=730|Radius=3|SecondaryRadius=3|LineWidth=1|Color=16711680
|RECORD=13|OwnerIndex=1448|IsNotAccesible=T|IndexInSheet=149|OwnerPartId=2|Location.X=1018|Location.Y=730|Corner.X=1040|Corner.Y=730|LineWidth=1|Color=16711680
|RECORD=8|OwnerIndex=1448|IsNotAccesible=T|IndexInSheet=150|OwnerPartId=2|Location.X=1015|Location.Y=710|Radius=3|SecondaryRadius=3|LineWidth=1|Color=16711680
|RECORD=13|OwnerIndex=1448|IsNotAccesible=T|IndexInSheet=151|OwnerPartId=2|Location.X=1018|Location.Y=710|Corner.X=1040|Corner.Y=710|LineWidth=1|Color=16711680
|RECORD=8|OwnerIndex=1448|IsNotAccesible=T|IndexInSheet=152|OwnerPartId=2|Location.X=1015|Location.Y=690|Radius=3|SecondaryRadius=3|LineWidth=1|Color=16711680
|RECORD=13|OwnerIndex=1448|IsNotAccesible=T|IndexInSheet=153|OwnerPartId=2|Location.X=1018|Location.Y=690|Corner.X=1040|Corner.Y=690|LineWidth=1|Color=16711680
|RECORD=8|OwnerIndex=1448|IsNotAccesible=T|IndexInSheet=154|OwnerPartId=2|Location.X=1015|Location.Y=670|Radius=3|SecondaryRadius=3|LineWidth=1|Color=16711680
|RECORD=13|OwnerIndex=1448|IsNotAccesible=T|IndexInSheet=155|OwnerPartId=2|Location.X=1018|Location.Y=670|Corner.X=1040|Corner.Y=670|LineWidth=1|Color=16711680
|RECORD=8|OwnerIndex=1448|IsNotAccesible=T|IndexInSheet=156|OwnerPartId=2|Location.X=1015|Location.Y=650|Radius=3|SecondaryRadius=3|LineWidth=1|Color=16711680
|RECORD=13|OwnerIndex=1448|IsNotAccesible=T|IndexInSheet=157|OwnerPartId=2|Location.X=1018|Location.Y=650|Corner.X=1040|Corner.Y=650|LineWidth=1|Color=16711680
|RECORD=8|OwnerIndex=1448|IsNotAccesible=T|IndexInSheet=158|OwnerPartId=2|Location.X=1015|Location.Y=630|Radius=3|SecondaryRadius=3|LineWidth=1|Color=16711680
|RECORD=13|OwnerIndex=1448|IsNotAccesible=T|IndexInSheet=159|OwnerPartId=2|Location.X=1018|Location.Y=630|Corner.X=1040|Corner.Y=630|LineWidth=1|Color=16711680
|RECORD=8|OwnerIndex=1448|IsNotAccesible=T|IndexInSheet=160|OwnerPartId=2|Location.X=1015|Location.Y=610|Radius=3|SecondaryRadius=3|LineWidth=1|Color=16711680
|RECORD=13|OwnerIndex=1448|IsNotAccesible=T|IndexInSheet=161|OwnerPartId=2|Location.X=1018|Location.Y=610|Corner.X=1040|Corner.Y=610|LineWidth=1|Color=16711680
|RECORD=8|OwnerIndex=1448|IsNotAccesible=T|IndexInSheet=162|OwnerPartId=2|Location.X=1015|Location.Y=590|Radius=3|SecondaryRadius=3|LineWidth=1|Color=16711680
|RECORD=13|OwnerIndex=1448|IsNotAccesible=T|IndexInSheet=163|OwnerPartId=2|Location.X=1018|Location.Y=590|Corner.X=1040|Corner.Y=590|LineWidth=1|Color=16711680
|RECORD=8|OwnerIndex=1448|IsNotAccesible=T|IndexInSheet=164|OwnerPartId=2|Location.X=1015|Location.Y=570|Radius=3|SecondaryRadius=3|LineWidth=1|Color=16711680
|RECORD=13|OwnerIndex=1448|IsNotAccesible=T|IndexInSheet=165|OwnerPartId=2|Location.X=1018|Location.Y=570|Corner.X=1040|Corner.Y=570|LineWidth=1|Color=16711680
|RECORD=8|OwnerIndex=1448|IsNotAccesible=T|IndexInSheet=166|OwnerPartId=2|Location.X=1015|Location.Y=550|Radius=3|SecondaryRadius=3|LineWidth=1|Color=16711680
|RECORD=13|OwnerIndex=1448|IsNotAccesible=T|IndexInSheet=167|OwnerPartId=2|Location.X=1018|Location.Y=550|Corner.X=1040|Corner.Y=550|LineWidth=1|Color=16711680
|RECORD=8|OwnerIndex=1448|IsNotAccesible=T|IndexInSheet=168|OwnerPartId=2|Location.X=1015|Location.Y=530|Radius=3|SecondaryRadius=3|LineWidth=1|Color=16711680
|RECORD=13|OwnerIndex=1448|IsNotAccesible=T|IndexInSheet=169|OwnerPartId=2|Location.X=1018|Location.Y=530|Corner.X=1040|Corner.Y=530|LineWidth=1|Color=16711680
|RECORD=8|OwnerIndex=1448|IsNotAccesible=T|IndexInSheet=170|OwnerPartId=2|Location.X=1015|Location.Y=510|Radius=3|SecondaryRadius=3|LineWidth=1|Color=16711680
|RECORD=13|OwnerIndex=1448|IsNotAccesible=T|IndexInSheet=171|OwnerPartId=2|Location.X=1018|Location.Y=510|Corner.X=1040|Corner.Y=510|LineWidth=1|Color=16711680
|RECORD=8|OwnerIndex=1448|IsNotAccesible=T|IndexInSheet=172|OwnerPartId=2|Location.X=1015|Location.Y=490|Radius=3|SecondaryRadius=3|LineWidth=1|Color=16711680
|RECORD=13|OwnerIndex=1448|IsNotAccesible=T|IndexInSheet=173|OwnerPartId=2|Location.X=1018|Location.Y=490|Corner.X=1040|Corner.Y=490|LineWidth=1|Color=16711680
|RECORD=8|OwnerIndex=1448|IsNotAccesible=T|IndexInSheet=174|OwnerPartId=2|Location.X=1015|Location.Y=470|Radius=3|SecondaryRadius=3|LineWidth=1|Color=16711680
|RECORD=13|OwnerIndex=1448|IsNotAccesible=T|IndexInSheet=175|OwnerPartId=2|Location.X=1018|Location.Y=470|Corner.X=1040|Corner.Y=470|LineWidth=1|Color=16711680
|RECORD=8|OwnerIndex=1448|IsNotAccesible=T|IndexInSheet=176|OwnerPartId=2|Location.X=1015|Location.Y=450|Radius=3|SecondaryRadius=3|LineWidth=1|Color=16711680
|RECORD=13|OwnerIndex=1448|IsNotAccesible=T|IndexInSheet=177|OwnerPartId=2|Location.X=1018|Location.Y=450|Corner.X=1040|Corner.Y=450|LineWidth=1|Color=16711680
|RECORD=8|OwnerIndex=1448|IsNotAccesible=T|IndexInSheet=178|OwnerPartId=2|Location.X=1015|Location.Y=430|Radius=3|SecondaryRadius=3|LineWidth=1|Color=16711680
|RECORD=13|OwnerIndex=1448|IsNotAccesible=T|IndexInSheet=179|OwnerPartId=2|Location.X=1018|Location.Y=430|Corner.X=1040|Corner.Y=430|LineWidth=1|Color=16711680
|RECORD=8|OwnerIndex=1448|IsNotAccesible=T|IndexInSheet=180|OwnerPartId=2|Location.X=1015|Location.Y=410|Radius=3|SecondaryRadius=3|LineWidth=1|Color=16711680
|RECORD=13|OwnerIndex=1448|IsNotAccesible=T|IndexInSheet=181|OwnerPartId=2|Location.X=1018|Location.Y=410|Corner.X=1040|Corner.Y=410|LineWidth=1|Color=16711680
|RECORD=8|OwnerIndex=1448|IsNotAccesible=T|IndexInSheet=182|OwnerPartId=2|Location.X=1015|Location.Y=390|Radius=3|SecondaryRadius=3|LineWidth=1|Color=16711680
|RECORD=13|OwnerIndex=1448|IsNotAccesible=T|IndexInSheet=183|OwnerPartId=2|Location.X=1018|Location.Y=390|Corner.X=1040|Corner.Y=390|LineWidth=1|Color=16711680
|RECORD=8|OwnerIndex=1448|IsNotAccesible=T|IndexInSheet=184|OwnerPartId=2|Location.X=1015|Location.Y=370|Radius=3|SecondaryRadius=3|LineWidth=1|Color=16711680
|RECORD=13|OwnerIndex=1448|IsNotAccesible=T|IndexInSheet=185|OwnerPartId=2|Location.X=1018|Location.Y=370|Corner.X=1040|Corner.Y=370|LineWidth=1|Color=16711680
|RECORD=8|OwnerIndex=1448|IsNotAccesible=T|IndexInSheet=186|OwnerPartId=2|Location.X=1015|Location.Y=350|Radius=3|SecondaryRadius=3|LineWidth=1|Color=16711680
|RECORD=13|OwnerIndex=1448|IsNotAccesible=T|IndexInSheet=187|OwnerPartId=2|Location.X=1018|Location.Y=350|Corner.X=1040|Corner.Y=350|LineWidth=1|Color=16711680
|RECORD=8|OwnerIndex=1448|IsNotAccesible=T|IndexInSheet=188|OwnerPartId=2|Location.X=1015|Location.Y=330|Radius=3|SecondaryRadius=3|LineWidth=1|Color=16711680
|RECORD=13|OwnerIndex=1448|IsNotAccesible=T|IndexInSheet=189|OwnerPartId=2|Location.X=1018|Location.Y=330|Corner.X=1040|Corner.Y=330|LineWidth=1|Color=16711680
|RECORD=8|OwnerIndex=1448|IsNotAccesible=T|IndexInSheet=190|OwnerPartId=2|Location.X=1015|Location.Y=310|Radius=3|SecondaryRadius=3|LineWidth=1|Color=16711680
|RECORD=13|OwnerIndex=1448|IsNotAccesible=T|IndexInSheet=191|OwnerPartId=2|Location.X=1018|Location.Y=310|Corner.X=1040|Corner.Y=310|LineWidth=1|Color=16711680
|RECORD=8|OwnerIndex=1448|IsNotAccesible=T|IndexInSheet=192|OwnerPartId=2|Location.X=1015|Location.Y=290|Radius=3|SecondaryRadius=3|LineWidth=1|Color=16711680
|RECORD=13|OwnerIndex=1448|IsNotAccesible=T|IndexInSheet=193|OwnerPartId=2|Location.X=1018|Location.Y=290|Corner.X=1040|Corner.Y=290|LineWidth=1|Color=16711680
|RECORD=8|OwnerIndex=1448|IsNotAccesible=T|IndexInSheet=194|OwnerPartId=2|Location.X=1015|Location.Y=270|Radius=3|SecondaryRadius=3|LineWidth=1|Color=16711680
|RECORD=13|OwnerIndex=1448|IsNotAccesible=T|IndexInSheet=195|OwnerPartId=2|Location.X=1018|Location.Y=270|Corner.X=1040|Corner.Y=270|LineWidth=1|Color=16711680
|RECORD=8|OwnerIndex=1448|IsNotAccesible=T|IndexInSheet=196|OwnerPartId=2|Location.X=1015|Location.Y=250|Radius=3|SecondaryRadius=3|LineWidth=1|Color=16711680
|RECORD=13|OwnerIndex=1448|IsNotAccesible=T|IndexInSheet=197|OwnerPartId=2|Location.X=1018|Location.Y=250|Corner.X=1040|Corner.Y=250|LineWidth=1|Color=16711680
|RECORD=8|OwnerIndex=1448|IsNotAccesible=T|IndexInSheet=198|OwnerPartId=2|Location.X=1015|Location.Y=230|Radius=3|SecondaryRadius=3|LineWidth=1|Color=16711680
|RECORD=13|OwnerIndex=1448|IsNotAccesible=T|IndexInSheet=199|OwnerPartId=2|Location.X=1018|Location.Y=230|Corner.X=1040|Corner.Y=230|LineWidth=1|Color=16711680
|RECORD=8|OwnerIndex=1448|IsNotAccesible=T|IndexInSheet=200|OwnerPartId=2|Location.X=1015|Location.Y=210|Radius=3|SecondaryRadius=3|LineWidth=1|Color=16711680
|RECORD=13|OwnerIndex=1448|IsNotAccesible=T|IndexInSheet=201|OwnerPartId=2|Location.X=1018|Location.Y=210|Corner.X=1040|Corner.Y=210|LineWidth=1|Color=16711680
|RECORD=8|OwnerIndex=1448|IsNotAccesible=T|IndexInSheet=202|OwnerPartId=2|Location.X=1015|Location.Y=190|Radius=3|SecondaryRadius=3|LineWidth=1|Color=16711680
|RECORD=13|OwnerIndex=1448|IsNotAccesible=T|IndexInSheet=203|OwnerPartId=2|Location.X=1018|Location.Y=190|Corner.X=1040|Corner.Y=190|LineWidth=1|Color=16711680
|RECORD=8|OwnerIndex=1448|IsNotAccesible=T|IndexInSheet=204|OwnerPartId=2|Location.X=1015|Location.Y=170|Radius=3|SecondaryRadius=3|LineWidth=1|Color=16711680
|RECORD=13|OwnerIndex=1448|IsNotAccesible=T|IndexInSheet=205|OwnerPartId=2|Location.X=1018|Location.Y=170|Corner.X=1040|Corner.Y=170|LineWidth=1|Color=16711680
|RECORD=8|OwnerIndex=1448|IsNotAccesible=T|IndexInSheet=206|OwnerPartId=2|Location.X=1015|Location.Y=150|Radius=3|SecondaryRadius=3|LineWidth=1|Color=16711680
|RECORD=13|OwnerIndex=1448|IsNotAccesible=T|IndexInSheet=207|OwnerPartId=2|Location.X=1018|Location.Y=150|Corner.X=1040|Corner.Y=150|LineWidth=1|Color=16711680
|RECORD=8|OwnerIndex=1448|IsNotAccesible=T|IndexInSheet=208|OwnerPartId=2|Location.X=1015|Location.Y=130|Radius=3|SecondaryRadius=3|LineWidth=1|Color=16711680
|RECORD=13|OwnerIndex=1448|IsNotAccesible=T|IndexInSheet=209|OwnerPartId=2|Location.X=1018|Location.Y=130|Corner.X=1040|Corner.Y=130|LineWidth=1|Color=16711680
|RECORD=4|OwnerIndex=1448|IsNotAccesible=T|IndexInSheet=210|OwnerPartId=2|Location.X=1033|Location.Y=802|Justification=8|Color=8388608|FontID=1|Text=2
|RECORD=4|OwnerIndex=1448|IsNotAccesible=T|IndexInSheet=211|OwnerPartId=2|Location.X=1033|Location.Y=782|Justification=8|Color=8388608|FontID=1|Text=4
|RECORD=4|OwnerIndex=1448|IsNotAccesible=T|IndexInSheet=212|OwnerPartId=2|Location.X=1033|Location.Y=762|Justification=8|Color=8388608|FontID=1|Text=6
|RECORD=4|OwnerIndex=1448|IsNotAccesible=T|IndexInSheet=213|OwnerPartId=2|Location.X=1033|Location.Y=742|Justification=8|Color=8388608|FontID=1|Text=8
|RECORD=4|OwnerIndex=1448|IsNotAccesible=T|IndexInSheet=214|OwnerPartId=2|Location.X=1033|Location.Y=722|Justification=8|Color=8388608|FontID=1|Text=10
|RECORD=4|OwnerIndex=1448|IsNotAccesible=T|IndexInSheet=215|OwnerPartId=2|Location.X=1033|Location.Y=702|Justification=8|Color=8388608|FontID=1|Text=20
|RECORD=4|OwnerIndex=1448|IsNotAccesible=T|IndexInSheet=216|OwnerPartId=2|Location.X=1033|Location.Y=682|Justification=8|Color=8388608|FontID=1|Text=22
|RECORD=4|OwnerIndex=1448|IsNotAccesible=T|IndexInSheet=217|OwnerPartId=2|Location.X=1033|Location.Y=662|Justification=8|Color=8388608|FontID=1|Text=24
|RECORD=4|OwnerIndex=1448|IsNotAccesible=T|IndexInSheet=218|OwnerPartId=2|Location.X=1033|Location.Y=642|Justification=8|Color=8388608|FontID=1|Text=26
|RECORD=4|OwnerIndex=1448|IsNotAccesible=T|IndexInSheet=219|OwnerPartId=2|Location.X=1033|Location.Y=622|Justification=8|Color=8388608|FontID=1|Text=28
|RECORD=4|OwnerIndex=1448|IsNotAccesible=T|IndexInSheet=220|OwnerPartId=2|Location.X=1033|Location.Y=602|Justification=8|Color=8388608|FontID=1|Text=30
|RECORD=4|OwnerIndex=1448|IsNotAccesible=T|IndexInSheet=221|OwnerPartId=2|Location.X=1033|Location.Y=582|Justification=8|Color=8388608|FontID=1|Text=32
|RECORD=4|OwnerIndex=1448|IsNotAccesible=T|IndexInSheet=222|OwnerPartId=2|Location.X=1033|Location.Y=562|Justification=8|Color=8388608|FontID=1|Text=34
|RECORD=4|OwnerIndex=1448|IsNotAccesible=T|IndexInSheet=223|OwnerPartId=2|Location.X=1033|Location.Y=542|Justification=8|Color=8388608|FontID=1|Text=36
|RECORD=4|OwnerIndex=1448|IsNotAccesible=T|IndexInSheet=224|OwnerPartId=2|Location.X=1033|Location.Y=522|Justification=8|Color=8388608|FontID=1|Text=38
|RECORD=4|OwnerIndex=1448|IsNotAccesible=T|IndexInSheet=225|OwnerPartId=2|Location.X=1033|Location.Y=502|Justification=8|Color=8388608|FontID=1|Text=40
|RECORD=4|OwnerIndex=1448|IsNotAccesible=T|IndexInSheet=226|OwnerPartId=2|Location.X=1033|Location.Y=482|Justification=8|Color=8388608|FontID=1|Text=42
|RECORD=4|OwnerIndex=1448|IsNotAccesible=T|IndexInSheet=227|OwnerPartId=2|Location.X=1033|Location.Y=462|Justification=8|Color=8388608|FontID=1|Text=44
|RECORD=4|OwnerIndex=1448|IsNotAccesible=T|IndexInSheet=228|OwnerPartId=2|Location.X=1033|Location.Y=442|Justification=8|Color=8388608|FontID=1|Text=46
|RECORD=4|OwnerIndex=1448|IsNotAccesible=T|IndexInSheet=229|OwnerPartId=2|Location.X=1033|Location.Y=422|Justification=8|Color=8388608|FontID=1|Text=48
|RECORD=4|OwnerIndex=1448|IsNotAccesible=T|IndexInSheet=230|OwnerPartId=2|Location.X=1033|Location.Y=402|Justification=8|Color=8388608|FontID=1|Text=50
|RECORD=4|OwnerIndex=1448|IsNotAccesible=T|IndexInSheet=231|OwnerPartId=2|Location.X=1033|Location.Y=382|Justification=8|Color=8388608|FontID=1|Text=52
|RECORD=4|OwnerIndex=1448|IsNotAccesible=T|IndexInSheet=232|OwnerPartId=2|Location.X=1033|Location.Y=362|Justification=8|Color=8388608|FontID=1|Text=54
|RECORD=4|OwnerIndex=1448|IsNotAccesible=T|IndexInSheet=233|OwnerPartId=2|Location.X=1033|Location.Y=342|Justification=8|Color=8388608|FontID=1|Text=56
|RECORD=4|OwnerIndex=1448|IsNotAccesible=T|IndexInSheet=234|OwnerPartId=2|Location.X=1033|Location.Y=322|Justification=8|Color=8388608|FontID=1|Text=58
|RECORD=4|OwnerIndex=1448|IsNotAccesible=T|IndexInSheet=235|OwnerPartId=2|Location.X=1033|Location.Y=302|Justification=8|Color=8388608|FontID=1|Text=60
|RECORD=4|OwnerIndex=1448|IsNotAccesible=T|IndexInSheet=236|OwnerPartId=2|Location.X=1033|Location.Y=282|Justification=8|Color=8388608|FontID=1|Text=62
|RECORD=4|OwnerIndex=1448|IsNotAccesible=T|IndexInSheet=237|OwnerPartId=2|Location.X=1033|Location.Y=262|Justification=8|Color=8388608|FontID=1|Text=64
|RECORD=4|OwnerIndex=1448|IsNotAccesible=T|IndexInSheet=238|OwnerPartId=2|Location.X=1033|Location.Y=242|Justification=8|Color=8388608|FontID=1|Text=66
|RECORD=4|OwnerIndex=1448|IsNotAccesible=T|IndexInSheet=239|OwnerPartId=2|Location.X=1033|Location.Y=222|Justification=8|Color=8388608|FontID=1|Text=68
|RECORD=4|OwnerIndex=1448|IsNotAccesible=T|IndexInSheet=240|OwnerPartId=2|Location.X=1033|Location.Y=202|Justification=8|Color=8388608|FontID=1|Text=70
|RECORD=4|OwnerIndex=1448|IsNotAccesible=T|IndexInSheet=241|OwnerPartId=2|Location.X=1033|Location.Y=182|Justification=8|Color=8388608|FontID=1|Text=72
|RECORD=4|OwnerIndex=1448|IsNotAccesible=T|IndexInSheet=242|OwnerPartId=2|Location.X=1033|Location.Y=162|Justification=8|Color=8388608|FontID=1|Text=74
|RECORD=4|OwnerIndex=1448|IsNotAccesible=T|IndexInSheet=243|OwnerPartId=2|Location.X=1033|Location.Y=142|Justification=8|Color=8388608|FontID=1|Text=MNT 1
|RECORD=2|OwnerIndex=1448|OwnerPartId=2|Electrical=4|PinConglomerate=48|PinLength=20|Location.X=1040|Location.Y=790|Name=2|Designator=2|PinName_PositionConglomerate=16|Name_CustomFontID=1|PinDesignator_PositionConglomerate=16|Designator_CustomFontID=1|PinPropagationDelay=0.000000E+000
|RECORD=2|OwnerIndex=1448|OwnerPartId=2|Electrical=4|PinConglomerate=48|PinLength=20|Location.X=1040|Location.Y=770|Name=4|Designator=4|PinName_PositionConglomerate=16|Name_CustomFontID=1|PinDesignator_PositionConglomerate=16|Designator_CustomFontID=1|PinPropagationDelay=0.000000E+000
|RECORD=2|OwnerIndex=1448|OwnerPartId=2|Electrical=4|PinConglomerate=48|PinLength=20|Location.X=1040|Location.Y=750|Name=6|Designator=6|PinName_PositionConglomerate=16|Name_CustomFontID=1|PinDesignator_PositionConglomerate=16|Designator_CustomFontID=1|PinPropagationDelay=0.000000E+000
|RECORD=2|OwnerIndex=1448|OwnerPartId=2|Electrical=4|PinConglomerate=48|PinLength=20|Location.X=1040|Location.Y=730|Name=8|Designator=8|PinName_PositionConglomerate=16|Name_CustomFontID=1|PinDesignator_PositionConglomerate=16|Designator_CustomFontID=1|PinPropagationDelay=0.000000E+000
|RECORD=2|OwnerIndex=1448|OwnerPartId=2|Electrical=4|PinConglomerate=48|PinLength=20|Location.X=1040|Location.Y=710|Name=10|Designator=10|PinName_PositionConglomerate=16|Name_CustomFontID=1|PinDesignator_PositionConglomerate=16|Designator_CustomFontID=1|PinPropagationDelay=0.000000E+000
|RECORD=2|OwnerIndex=1448|OwnerPartId=2|Electrical=4|PinConglomerate=48|PinLength=20|Location.X=1040|Location.Y=690|Name=20|Designator=20|PinName_PositionConglomerate=16|Name_CustomFontID=1|PinDesignator_PositionConglomerate=16|Designator_CustomFontID=1|PinPropagationDelay=0.000000E+000
|RECORD=2|OwnerIndex=1448|OwnerPartId=2|Electrical=4|PinConglomerate=48|PinLength=20|Location.X=1040|Location.Y=670|Name=22|Designator=22|PinName_PositionConglomerate=16|Name_CustomFontID=1|PinDesignator_PositionConglomerate=16|Designator_CustomFontID=1|PinPropagationDelay=0.000000E+000
|RECORD=2|OwnerIndex=1448|OwnerPartId=2|Electrical=4|PinConglomerate=48|PinLength=20|Location.X=1040|Location.Y=650|Name=24|Designator=24|PinName_PositionConglomerate=16|Name_CustomFontID=1|PinDesignator_PositionConglomerate=16|Designator_CustomFontID=1|PinPropagationDelay=0.000000E+000
|RECORD=2|OwnerIndex=1448|OwnerPartId=2|Electrical=4|PinConglomerate=48|PinLength=20|Location.X=1040|Location.Y=630|Name=26|Designator=26|PinName_PositionConglomerate=16|Name_CustomFontID=1|PinDesignator_PositionConglomerate=16|Designator_CustomFontID=1|PinPropagationDelay=0.000000E+000
|RECORD=2|OwnerIndex=1448|OwnerPartId=2|Electrical=4|PinConglomerate=48|PinLength=20|Location.X=1040|Location.Y=610|Name=28|Designator=28|PinName_PositionConglomerate=16|Name_CustomFontID=1|PinDesignator_PositionConglomerate=16|Designator_CustomFontID=1|PinPropagationDelay=0.000000E+000
|RECORD=2|OwnerIndex=1448|OwnerPartId=2|Electrical=4|PinConglomerate=48|PinLength=20|Location.X=1040|Location.Y=590|Name=30|Designator=30|PinName_PositionConglomerate=16|Name_CustomFontID=1|PinDesignator_PositionConglomerate=16|Designator_CustomFontID=1|PinPropagationDelay=0.000000E+000
|RECORD=2|OwnerIndex=1448|OwnerPartId=2|Electrical=4|PinConglomerate=48|PinLength=20|Location.X=1040|Location.Y=570|Name=32|Designator=32|PinName_PositionConglomerate=16|Name_CustomFontID=1|PinDesignator_PositionConglomerate=16|Designator_CustomFontID=1|PinPropagationDelay=0.000000E+000
|RECORD=2|OwnerIndex=1448|OwnerPartId=2|Electrical=4|PinConglomerate=48|PinLength=20|Location.X=1040|Location.Y=550|Name=34|Designator=34|PinName_PositionConglomerate=16|Name_CustomFontID=1|PinDesignator_PositionConglomerate=16|Designator_CustomFontID=1|PinPropagationDelay=0.000000E+000
|RECORD=2|OwnerIndex=1448|OwnerPartId=2|Electrical=4|PinConglomerate=48|PinLength=20|Location.X=1040|Location.Y=530|Name=36|Designator=36|PinName_PositionConglomerate=16|Name_CustomFontID=1|PinDesignator_PositionConglomerate=16|Designator_CustomFontID=1|PinPropagationDelay=0.000000E+000
|RECORD=2|OwnerIndex=1448|OwnerPartId=2|Electrical=4|PinConglomerate=48|PinLength=20|Location.X=1040|Location.Y=510|Name=38|Designator=38|PinName_PositionConglomerate=16|Name_CustomFontID=1|PinDesignator_PositionConglomerate=16|Designator_CustomFontID=1|PinPropagationDelay=0.000000E+000
|RECORD=2|OwnerIndex=1448|OwnerPartId=2|Electrical=4|PinConglomerate=48|PinLength=20|Location.X=1040|Location.Y=490|Name=40|Designator=40|PinName_PositionConglomerate=16|Name_CustomFontID=1|PinDesignator_PositionConglomerate=16|Designator_CustomFontID=1|PinPropagationDelay=0.000000E+000
|RECORD=2|OwnerIndex=1448|OwnerPartId=2|Electrical=4|PinConglomerate=48|PinLength=20|Location.X=1040|Location.Y=470|Name=42|Designator=42|PinName_PositionConglomerate=16|Name_CustomFontID=1|PinDesignator_PositionConglomerate=16|Designator_CustomFontID=1|PinPropagationDelay=0.000000E+000
|RECORD=2|OwnerIndex=1448|OwnerPartId=2|Electrical=4|PinConglomerate=48|PinLength=20|Location.X=1040|Location.Y=450|Name=44|Designator=44|PinName_PositionConglomerate=16|Name_CustomFontID=1|PinDesignator_PositionConglomerate=16|Designator_CustomFontID=1|PinPropagationDelay=0.000000E+000
|RECORD=2|OwnerIndex=1448|OwnerPartId=2|Electrical=4|PinConglomerate=48|PinLength=20|Location.X=1040|Location.Y=430|Name=46|Designator=46|PinName_PositionConglomerate=16|Name_CustomFontID=1|PinDesignator_PositionConglomerate=16|Designator_CustomFontID=1|PinPropagationDelay=0.000000E+000
|RECORD=2|OwnerIndex=1448|OwnerPartId=2|Electrical=4|PinConglomerate=48|PinLength=20|Location.X=1040|Location.Y=410|Name=48|Designator=48|PinName_PositionConglomerate=16|Name_CustomFontID=1|PinDesignator_PositionConglomerate=16|Designator_CustomFontID=1|PinPropagationDelay=0.000000E+000
|RECORD=2|OwnerIndex=1448|OwnerPartId=2|Electrical=4|PinConglomerate=48|PinLength=20|Location.X=1040|Location.Y=390|Name=50|Designator=50|PinName_PositionConglomerate=16|Name_CustomFontID=1|PinDesignator_PositionConglomerate=16|Designator_CustomFontID=1|PinPropagationDelay=0.000000E+000
|RECORD=2|OwnerIndex=1448|OwnerPartId=2|Electrical=4|PinConglomerate=48|PinLength=20|Location.X=1040|Location.Y=370|Name=52|Designator=52|PinName_PositionConglomerate=16|Name_CustomFontID=1|PinDesignator_PositionConglomerate=16|Designator_CustomFontID=1|PinPropagationDelay=0.000000E+000
|RECORD=2|OwnerIndex=1448|OwnerPartId=2|Electrical=4|PinConglomerate=48|PinLength=20|Location.X=1040|Location.Y=350|Name=54|Designator=54|PinName_PositionConglomerate=16|Name_CustomFontID=1|PinDesignator_PositionConglomerate=16|Designator_CustomFontID=1|PinPropagationDelay=0.000000E+000
|RECORD=2|OwnerIndex=1448|OwnerPartId=2|Electrical=4|PinConglomerate=48|PinLength=20|Location.X=1040|Location.Y=330|Name=56|Designator=56|PinName_PositionConglomerate=16|Name_CustomFontID=1|PinDesignator_PositionConglomerate=16|Designator_CustomFontID=1|PinPropagationDelay=0.000000E+000
|RECORD=2|OwnerIndex=1448|OwnerPartId=2|Electrical=4|PinConglomerate=48|PinLength=20|Location.X=1040|Location.Y=310|Name=58|Designator=58|PinName_PositionConglomerate=16|Name_CustomFontID=1|PinDesignator_PositionConglomerate=16|Designator_CustomFontID=1|PinPropagationDelay=0.000000E+000
|RECORD=2|OwnerIndex=1448|OwnerPartId=2|Electrical=4|PinConglomerate=48|PinLength=20|Location.X=1040|Location.Y=290|Name=60|Designator=60|PinName_PositionConglomerate=16|Name_CustomFontID=1|PinDesignator_PositionConglomerate=16|Designator_CustomFontID=1|PinPropagationDelay=0.000000E+000
|RECORD=2|OwnerIndex=1448|OwnerPartId=2|Electrical=4|PinConglomerate=48|PinLength=20|Location.X=1040|Location.Y=270|Name=62|Designator=62|PinName_PositionConglomerate=16|Name_CustomFontID=1|PinDesignator_PositionConglomerate=16|Designator_CustomFontID=1|PinPropagationDelay=0.000000E+000
|RECORD=2|OwnerIndex=1448|OwnerPartId=2|Electrical=4|PinConglomerate=48|PinLength=20|Location.X=1040|Location.Y=250|Name=64|Designator=64|PinName_PositionConglomerate=16|Name_CustomFontID=1|PinDesignator_PositionConglomerate=16|Designator_CustomFontID=1|PinPropagationDelay=0.000000E+000
|RECORD=2|OwnerIndex=1448|OwnerPartId=2|Electrical=4|PinConglomerate=48|PinLength=20|Location.X=1040|Location.Y=230|Name=66|Designator=66|PinName_PositionConglomerate=16|Name_CustomFontID=1|PinDesignator_PositionConglomerate=16|Designator_CustomFontID=1|PinPropagationDelay=0.000000E+000
|RECORD=2|OwnerIndex=1448|OwnerPartId=2|Electrical=4|PinConglomerate=48|PinLength=20|Location.X=1040|Location.Y=210|Name=68|Designator=68|PinName_PositionConglomerate=16|Name_CustomFontID=1|PinDesignator_PositionConglomerate=16|Designator_CustomFontID=1|PinPropagationDelay=0.000000E+000
|RECORD=2|OwnerIndex=1448|OwnerPartId=2|Electrical=4|PinConglomerate=48|PinLength=20|Location.X=1040|Location.Y=190|Name=70|Designator=70|PinName_PositionConglomerate=16|Name_CustomFontID=1|PinDesignator_PositionConglomerate=16|Designator_CustomFontID=1|PinPropagationDelay=0.000000E+000
|RECORD=2|OwnerIndex=1448|OwnerPartId=2|Electrical=4|PinConglomerate=48|PinLength=20|Location.X=1040|Location.Y=170|Name=72|Designator=72|PinName_PositionConglomerate=16|Name_CustomFontID=1|PinDesignator_PositionConglomerate=16|Designator_CustomFontID=1|PinPropagationDelay=0.000000E+000
|RECORD=2|OwnerIndex=1448|OwnerPartId=2|Electrical=4|PinConglomerate=48|PinLength=20|Location.X=1040|Location.Y=150|Name=74|Designator=74|PinName_PositionConglomerate=16|Name_CustomFontID=1|PinDesignator_PositionConglomerate=16|Designator_CustomFontID=1|PinPropagationDelay=0.000000E+000
|RECORD=2|OwnerIndex=1448|OwnerPartId=2|Electrical=4|PinConglomerate=48|PinLength=20|Location.X=1040|Location.Y=130|Name=MNT 1|Designator=76|PinName_PositionConglomerate=16|Name_CustomFontID=1|PinDesignator_PositionConglomerate=16|Designator_CustomFontID=1|PinPropagationDelay=0.000000E+000
|RECORD=41|OwnerIndex=1448|IndexInSheet=278|OwnerPartId=-1|Location.X=990|Location.Y=810|Color=8388608|FontID=1|IsHidden=T|Text=500mA|Name=Contact Current Rating
|RECORD=41|OwnerIndex=1448|IndexInSheet=279|OwnerPartId=-1|Location.X=990|Location.Y=810|Color=8388608|FontID=1|IsHidden=T|Text=67|Name=Number of Contacts
|RECORD=41|OwnerIndex=1448|IndexInSheet=280|OwnerPartId=-1|Location.X=990|Location.Y=810|Color=8388608|FontID=1|IsHidden=T|Text=Right Angle|Name=Orientation
|RECORD=41|OwnerIndex=1448|IndexInSheet=281|OwnerPartId=-1|Location.X=990|Location.Y=810|Color=8388608|FontID=1|IsHidden=T|Text=0.862inch|Name=Length
|RECORD=41|OwnerIndex=1448|IndexInSheet=282|OwnerPartId=-1|Location.X=990|Location.Y=810|Color=8388608|FontID=1|IsHidden=T|Text=No|Name=Radiation Hardening
|RECORD=41|OwnerIndex=1448|IndexInSheet=283|OwnerPartId=-1|Location.X=990|Location.Y=810|Color=8388608|FontID=1|IsHidden=T|Text=Right Angle|Name=PCB Mounting Orientation
|RECORD=41|OwnerIndex=1448|IndexInSheet=284|OwnerPartId=-1|Location.X=990|Location.Y=810|Color=8388608|FontID=1|IsHidden=T|Text=Surface Mount|Name=Mount
|RECORD=41|OwnerIndex=1448|IndexInSheet=285|OwnerPartId=-1|Location.X=990|Location.Y=810|Color=8388608|FontID=1|IsHidden=T|Text=Gold|Name=Contact Plating
|RECORD=41|OwnerIndex=1448|IndexInSheet=286|OwnerPartId=-1|Location.X=990|Location.Y=810|Color=8388608|FontID=1|IsHidden=T|Text=Copper Alloy|Name=Contact Material
|RECORD=41|OwnerIndex=1448|IndexInSheet=287|OwnerPartId=-1|Location.X=990|Location.Y=810|Color=8388608|FontID=1|IsHidden=T|Text=8.7mm|Name=Width
|RECORD=41|OwnerIndex=1448|IndexInSheet=288|OwnerPartId=-1|Location.X=990|Location.Y=810|Color=8388608|FontID=1|IsHidden=T|Text=2|Name=Number of Rows
|RECORD=41|OwnerIndex=1448|IndexInSheet=289|OwnerPartId=-1|Location.X=990|Location.Y=810|Color=8388608|FontID=1|IsHidden=T|Text=Black|Name=Color
|RECORD=41|OwnerIndex=1448|IndexInSheet=290|OwnerPartId=-1|Location.X=990|Location.Y=810|Color=8388608|FontID=1|IsHidden=T|Text=0.5mm|Name=Pitch
|RECORD=41|OwnerIndex=1448|IndexInSheet=291|OwnerPartId=-1|Location.X=990|Location.Y=810|Color=8388608|FontID=1|IsHidden=T|Text=Compliant|Name=ELV
|RECORD=41|OwnerIndex=1448|IndexInSheet=292|OwnerPartId=-1|Location.X=990|Location.Y=810|Color=8388608|FontID=1|IsHidden=T|Text=Black|Name=Housing Color
|RECORD=41|OwnerIndex=1448|IndexInSheet=293|OwnerPartId=-1|Location.X=990|Location.Y=810|Color=8388608|FontID=1|IsHidden=T|Text=50V|Name=Voltage Rating
|RECORD=41|OwnerIndex=1448|IndexInSheet=294|OwnerPartId=-1|Location.X=990|Location.Y=810|Color=8388608|FontID=1|IsHidden=T|Text=67|Name=Number of Positions
|RECORD=41|OwnerIndex=1448|IndexInSheet=295|OwnerPartId=-1|Location.X=990|Location.Y=810|Color=8388608|FontID=1|IsHidden=T|Text=Thermoplastic|Name=Housing Material
|RECORD=41|OwnerIndex=1448|IndexInSheet=296|OwnerPartId=-1|Location.X=990|Location.Y=810|Color=8388608|FontID=1|IsHidden=T|Text=Female|Name=Gender
|RECORD=41|OwnerIndex=1448|IndexInSheet=297|OwnerPartId=-1|Location.X=990|Location.Y=810|Color=8388608|FontID=1|IsHidden=T|Text=-40°C|Name=Min Operating Temperature
|RECORD=41|OwnerIndex=1448|IndexInSheet=298|OwnerPartId=-1|Location.X=990|Location.Y=810|Color=8388608|FontID=1|IsHidden=T|Text=80°C|Name=Max Operating Temperature
|RECORD=41|OwnerIndex=1448|IndexInSheet=299|OwnerPartId=-1|Location.X=990|Location.Y=810|Color=8388608|FontID=1|IsHidden=T|Text=500MR|Name=Insulation Resistance
|RECORD=41|OwnerIndex=1448|IndexInSheet=300|OwnerPartId=-1|Location.X=990|Location.Y=810|Color=8388608|FontID=1|IsHidden=T|Text=7.55mm|Name=Row Spacing
|RECORD=41|OwnerIndex=1448|IndexInSheet=301|OwnerPartId=-1|Location.X=990|Location.Y=810|Color=8388608|FontID=1|IsHidden=T|Text=Yes|Name=RoHS Compliant
|RECORD=41|OwnerIndex=1448|IndexInSheet=302|OwnerPartId=-1|Location.X=990|Location.Y=810|Color=8388608|FontID=1|IsHidden=T|Text=1200|Name=Package Quantity
|RECORD=41|OwnerIndex=1448|IndexInSheet=303|OwnerPartId=-1|Location.X=990|Location.Y=810|Color=8388608|FontID=1|IsHidden=T|Text=Tape and Reel|Name=Packaging
|RECORD=41|OwnerIndex=1448|IndexInSheet=304|OwnerPartId=-1|Location.X=990|Location.Y=810|Color=8388608|FontID=1|IsHidden=T|Text=3.2mm|Name=Height
|RECORD=41|OwnerIndex=1448|IndexInSheet=305|OwnerPartId=-1|Location.X=990|Location.Y=810|Color=8388608|FontID=1|IsHidden=T|Text=Solder|Name=Termination
|RECORD=41|OwnerIndex=1448|IndexInSheet=306|OwnerPartId=-1|Location.X=990|Location.Y=810|Color=8388608|FontID=1|IsHidden=T|Text=Thermoplastic|Name=Insulation Material
|RECORD=41|OwnerIndex=1448|IndexInSheet=307|OwnerPartId=-1|Location.X=990|Location.Y=810|Color=8388608|FontID=1|IsHidden=T|Text=50V|Name=Max Voltage Rating (AC)
|RECORD=41|OwnerIndex=1448|IndexInSheet=308|OwnerPartId=-1|Location.X=990|Location.Y=810|Color=8388608|FontID=1|IsHidden=T|Text=500mA|Name=Current Rating
|RECORD=34|OwnerIndex=1448|IndexInSheet=-1|OwnerPartId=-1|Location.X=990|Location.Y=810|Color=8388608|FontID=1|Text=J45|Name=Designator|ReadOnlyState=1
|RECORD=41|OwnerIndex=1448|IndexInSheet=-1|OwnerPartId=1|Location.X=990|Location.Y=100|Color=8388608|FontID=1|Text=2199119-3|Name=Comment
|RECORD=44|OwnerIndex=1448
|RECORD=45|OwnerIndex=1829|IndexInSheet=-1|UseComponentLibrary=T|ModelName=FP-2199119-3-MFG|ModelType=PCBLIB|DatafileCount=1|ModelDatafileEntity0=FP-2199119-3-MFG|ModelDatafileKind0=PCBLib|IsCurrent=T|DatalinksLocked=T|DatabaseDatalinksLocked=T
|RECORD=46|OwnerIndex=1830
|RECORD=48|OwnerIndex=1830
|RECORD=4|IndexInSheet=105|OwnerPartId=-1|Location.X=1210|Location.Y=690|Color=8388608|FontID=1|Text=10MHz to module
|RECORD=28|IndexInSheet=106|OwnerPartId=-1|Location.X=1230|Location.Y=650|Corner.X=1299|Corner.X_Frac=25477|Corner.Y=662|Corner.Y_Frac=10|AreaColor=16777215|FontID=1|IsSolid=T|Alignment=1|WordWrap=T|ClipToRect=T|Text=1PPS to Module|TextMargin_Frac=5
|RECORD=1|LibReference=RES-2|ComponentDescription=Chip Resistor, 0 Ohm, 0.1 W, -55 to 155 degC, 0402 (1005 Metric), RoHS, Tape and Reel|PartCount=2|DisplayModeCount=1|IndexInSheet=107|OwnerPartId=-1|Location.X=830|Location.Y=540|CurrentPartId=1|LibraryPath=*|SourceLibraryName=Altium Content Vault|TargetFileName=*|AreaColor=11599871|Color=128|PartIDLocked=T|DesignItemId=CMP-2000-07451-1|AllPinCount=2|ComponentKindVersion2=5
|RECORD=2|OwnerIndex=1835|OwnerPartId=1|FormalType=1|Electrical=4|PinConglomerate=32|PinLength=10|Location.X=850|Location.Y=540|Name=2|Designator=2|PinPropagationDelay=0.000000E+000
|RECORD=2|OwnerIndex=1835|OwnerPartId=1|FormalType=1|Electrical=4|PinConglomerate=34|PinLength=10|Location.X=830|Location.Y=540|Name=1|Designator=1|PinPropagationDelay=0.000000E+000
|RECORD=6|OwnerIndex=1835|IsNotAccesible=T|IndexInSheet=2|OwnerPartId=1|LineWidth=1|Color=16711680|LocationCount=10|X1=850|Y1=540|X2=846|Y2=540|X3=845|Y3=538|X4=843|Y4=542|X5=841|Y5=538|X6=839|Y6=542|X7=837|Y7=538|X8=835|Y8=542|X9=834|Y9=540|X10=830|Y10=540
|RECORD=41|OwnerIndex=1835|IndexInSheet=3|OwnerPartId=-1|Location.X=818|Location.Y=555|Color=8388608|FontID=1|IsHidden=T|Text=50V|Name=Voltage Rating (DC)
|RECORD=41|OwnerIndex=1835|IndexInSheet=4|OwnerPartId=-1|Location.X=818|Location.Y=555|Color=8388608|FontID=1|IsHidden=T|Text=2|Name=Number of Terminations
|RECORD=41|OwnerIndex=1835|IndexInSheet=5|OwnerPartId=-1|Location.X=818|Location.Y=555|Color=8388608|FontID=1|IsHidden=T|Text=SurfaceMount|Name=Mount
|RECORD=41|OwnerIndex=1835|IndexInSheet=6|OwnerPartId=-1|Location.X=818|Location.Y=555|Color=8388608|FontID=1|IsHidden=T|Text=0.35mm|Name=Height
|RECORD=41|OwnerIndex=1835|IndexInSheet=7|OwnerPartId=-1|Location.X=818|Location.Y=555|Color=8388608|FontID=1|IsHidden=T|Text=TapeandReel|Name=Packaging
|RECORD=41|OwnerIndex=1835|IndexInSheet=8|OwnerPartId=-1|Location.X=818|Location.Y=555|Color=8388608|FontID=1|IsHidden=T|Text=Tin|Name=Contact Plating
|RECORD=41|OwnerIndex=1835|IndexInSheet=9|OwnerPartId=-1|Location.X=818|Location.Y=555|Color=8388608|FontID=3|IsHidden=T|Text=http://www.panasonic.com/|Name=Manufacturer URL
|RECORD=41|OwnerIndex=1835|IndexInSheet=10|OwnerPartId=-1|Location.X=818|Location.Y=555|Color=8388608|FontID=1|IsHidden=T|Text=ThickFilm|Name=Composition
|RECORD=41|OwnerIndex=1835|IndexInSheet=11|OwnerPartId=-1|Location.X=818|Location.Y=555|Color=8388608|FontID=1|IsHidden=T|Text=155degC|Name=Max Operating Temperature
|RECORD=41|OwnerIndex=1835|IndexInSheet=12|OwnerPartId=-1|Location.X=818|Location.Y=555|Color=8388608|FontID=1|IsHidden=T|Text=600ppm/??C|Name=Temperature Coefficient
|RECORD=41|OwnerIndex=1835|IndexInSheet=13|OwnerPartId=-1|Location.X=818|Location.Y=555|Color=8388608|FontID=1|IsHidden=T|Text=NoSVHC|Name=REACH SVHC
|RECORD=41|OwnerIndex=1835|IndexInSheet=14|OwnerPartId=-1|Location.X=818|Location.Y=555|Color=8388608|FontID=1|IsHidden=T|Text=0402|Name=Case/Package
|RECORD=41|OwnerIndex=1835|IndexInSheet=15|OwnerPartId=-1|Location.X=818|Location.Y=555|Color=8388608|FontID=1|IsHidden=T|Text=100mW|Name=Max Power Dissipation
|RECORD=41|OwnerIndex=1835|IndexInSheet=16|OwnerPartId=-1|Location.X=818|Location.Y=555|Color=8388608|FontID=1|IsHidden=T|Text=402|Name=Package Reference
|RECORD=41|OwnerIndex=1835|IndexInSheet=17|OwnerPartId=-1|Location.X=818|Location.Y=555|Color=8388608|FontID=1|IsHidden=T|Text=0.5mm|Name=Depth
|RECORD=41|OwnerIndex=1835|IndexInSheet=18|OwnerPartId=-1|Location.X=818|Location.Y=555|Color=8388608|FontID=1|IsHidden=T|Text=Panasonic|Name=Manufacturer
|RECORD=41|OwnerIndex=1835|IndexInSheet=19|OwnerPartId=-1|Location.X=818|Location.Y=555|Color=8388608|FontID=1|IsHidden=T|Text=2-Pin Surface Mount Device, Body 1 x 0.5 mm|Name=Package Description
|RECORD=41|OwnerIndex=1835|IndexInSheet=20|OwnerPartId=-1|Location.X=818|Location.Y=555|Color=8388608|FontID=3|IsHidden=T|Text=https://industrial.panasonic.com/cdbs/www-data/pdf/RDA0000/AOA0000C301.pdf|Name=Datasheet URL
|RECORD=41|OwnerIndex=1835|IndexInSheet=21|OwnerPartId=-1|Location.X=818|Location.Y=555|Color=8388608|FontID=1|IsHidden=T|Text=True|Name=RoHSCompliant
|RECORD=41|OwnerIndex=1835|IndexInSheet=22|OwnerPartId=-1|Location.X=818|Location.Y=555|Color=8388608|FontID=1|IsHidden=T|Text=0402|Name=Case Code (Imperial)
|RECORD=41|OwnerIndex=1835|IndexInSheet=23|OwnerPartId=-1|Location.X=818|Location.Y=555|Color=8388608|FontID=1|IsHidden=T|Text=0mOhm|Name=Resistance
|RECORD=41|OwnerIndex=1835|IndexInSheet=24|OwnerPartId=-1|Location.X=818|Location.Y=555|Color=8388608|FontID=1|IsHidden=T|Text=Not|Name=Military Standard
|RECORD=41|OwnerIndex=1835|IndexInSheet=25|OwnerPartId=-1|Location.X=818|Location.Y=555|Color=8388608|FontID=1|IsHidden=T|Text=5%|Name=Tolerance
|RECORD=41|OwnerIndex=1835|IndexInSheet=26|OwnerPartId=-1|Location.X=818|Location.Y=555|Color=8388608|FontID=1|IsHidden=T|Text=-55degC|Name=Min Operating Temperature
|RECORD=41|OwnerIndex=1835|IndexInSheet=27|OwnerPartId=-1|Location.X=818|Location.Y=555|Color=8388608|FontID=1|IsHidden=T|Text=100mW|Name=Power Rating
|RECORD=41|OwnerIndex=1835|IndexInSheet=28|OwnerPartId=-1|Location.X=818|Location.Y=555|Color=8388608|FontID=1|IsHidden=T|Text=03/2015|Name=Datasheet Version
|RECORD=41|OwnerIndex=1835|IndexInSheet=29|OwnerPartId=-1|Location.X=818|Location.Y=555|Color=8388608|FontID=1|IsHidden=T|Text=1mm|Name=Length
|RECORD=41|OwnerIndex=1835|IndexInSheet=30|OwnerPartId=-1|Location.X=818|Location.Y=555|Color=8388608|FontID=1|IsHidden=T|Text=1005|Name=Case Code (Metric)
|RECORD=41|OwnerIndex=1835|IndexInSheet=31|OwnerPartId=-1|Location.X=818|Location.Y=555|Color=8388608|FontID=1|IsHidden=T|Text=SMD/SMT|Name=Termination
|RECORD=41|OwnerIndex=1835|IndexInSheet=32|OwnerPartId=-1|Location.X=818|Location.Y=555|Color=8388608|FontID=1|IsHidden=T|Text=SurfaceMount|Name=Mounting Technology
|RECORD=41|OwnerIndex=1835|IndexInSheet=33|OwnerPartId=-1|Location.X=818|Location.Y=555|Color=8388608|FontID=1|IsHidden=T|Text=50V|Name=Voltage Rating
|RECORD=41|OwnerIndex=1835|IndexInSheet=34|OwnerPartId=-1|Location.X=818|Location.Y=555|Color=8388608|FontID=1|IsHidden=T|Text=0.02inch|Name=Width
|RECORD=41|OwnerIndex=1835|IndexInSheet=35|OwnerPartId=-1|Location.X=818|Location.Y=555|Color=8388608|FontID=1|IsHidden=T|Text=1|Name=Package Quantity
|RECORD=41|OwnerIndex=1835|IndexInSheet=36|OwnerPartId=-1|Location.X=818|Location.Y=555|Color=8388608|FontID=1|IsHidden=T|Text=LeadFree|Name=Lead Free
|RECORD=41|OwnerIndex=1835|IndexInSheet=37|OwnerPartId=-1|Location.X=818|Location.Y=555|Color=8388608|FontID=1|IsHidden=T|Text=No|Name=Radiation Hardening
|RECORD=34|OwnerIndex=1835|IndexInSheet=-1|OwnerPartId=-1|Location.X=810|Location.Y=540|Color=8388608|FontID=1|Text=R131|Name=Designator|ReadOnlyState=1
|RECORD=41|OwnerIndex=1835|IndexInSheet=-1|OwnerPartId=-1|Location.X=850|Location.Y=540|Color=8388608|FontID=1|Text=DNI_0_1%_0402|Name=Comment
|RECORD=44|OwnerIndex=1835
|RECORD=45|OwnerIndex=1878|IndexInSheet=-1|Description=Chip Resistor, 2-Leads, Body 1.05x0.55mm, IPC High Density|UseComponentLibrary=T|ModelName=RESC1005X40X25LL05T05|ModelType=PCBLIB|DatafileCount=1|ModelDatafileEntity0=RESC1005X40X25LL05T05|ModelDatafileKind0=PCBLib|IsCurrent=T|DatalinksLocked=T|DatabaseDatalinksLocked=T
|RECORD=46|OwnerIndex=1879
|RECORD=48|OwnerIndex=1879
|RECORD=41|OwnerIndex=1881|IndexInSheet=-1|OwnerPartId=-1|Color=8388608|FontID=1|IsHidden=T|Text=2D|Name=Available Preview Images
|RECORD=45|OwnerIndex=1878|IndexInSheet=-1|Description=Chip Resistor, 2-Leads, Body 1.05x0.55mm, IPC Low Density|UseComponentLibrary=T|ModelName=RESC1005X40X25ML05T05|ModelType=PCBLIB|DatafileCount=1|ModelDatafileEntity0=RESC1005X40X25ML05T05|ModelDatafileKind0=PCBLib|DatalinksLocked=T|DatabaseDatalinksLocked=T
|RECORD=46|OwnerIndex=1883
|RECORD=48|OwnerIndex=1883
|RECORD=41|OwnerIndex=1885|IndexInSheet=-1|OwnerPartId=-1|Color=8388608|FontID=1|IsHidden=T|Text=2D|Name=Available Preview Images
|RECORD=45|OwnerIndex=1878|IndexInSheet=-1|Description=Chip Resistor, 2-Leads, Body 1.05x0.55mm, IPC Medium Density|UseComponentLibrary=T|ModelName=RESC1005X40X25NL05T05|ModelType=PCBLIB|DatafileCount=1|ModelDatafileEntity0=RESC1005X40X25NL05T05|ModelDatafileKind0=PCBLib|DatalinksLocked=T|DatabaseDatalinksLocked=T
|RECORD=46|OwnerIndex=1887
|RECORD=48|OwnerIndex=1887
|RECORD=41|OwnerIndex=1889|IndexInSheet=-1|OwnerPartId=-1|Color=8388608|FontID=1|IsHidden=T|Text=2D|Name=Available Preview Images
|RECORD=4|IndexInSheet=108|OwnerPartId=-1|Location.X=810|Location.Y=560|Color=8388608|FontID=1|Text=1PPS out here on some cards
|RECORD=1|LibReference=RES-2|ComponentDescription=Chip Resistor, 0 Ohm, 0.1 W, -55 to 155 degC, 0402 (1005 Metric), RoHS, Tape and Reel|PartCount=2|DisplayModeCount=1|IndexInSheet=109|OwnerPartId=-1|Location.X=1120|Location.Y=430|CurrentPartId=1|LibraryPath=*|SourceLibraryName=Altium Content Vault|TargetFileName=*|AreaColor=11599871|Color=128|PartIDLocked=T|DesignItemId=CMP-2000-07451-1|AllPinCount=2
|RECORD=2|OwnerIndex=1892|OwnerPartId=1|FormalType=1|Electrical=4|PinConglomerate=32|PinLength=10|Location.X=1140|Location.Y=430|Name=2|Designator=2|PinPropagationDelay=0.000000E+000
|RECORD=2|OwnerIndex=1892|OwnerPartId=1|FormalType=1|Electrical=4|PinConglomerate=34|PinLength=10|Location.X=1120|Location.Y=430|Name=1|Designator=1|PinPropagationDelay=0.000000E+000
|RECORD=6|OwnerIndex=1892|IsNotAccesible=T|IndexInSheet=2|OwnerPartId=1|LineWidth=1|Color=16711680|LocationCount=10|X1=1140|Y1=430|X2=1136|Y2=430|X3=1135|Y3=428|X4=1133|Y4=432|X5=1131|Y5=428|X6=1129|Y6=432|X7=1127|Y7=428|X8=1125|Y8=432|X9=1124|Y9=430|X10=1120|Y10=430
|RECORD=41|OwnerIndex=1892|IndexInSheet=3|OwnerPartId=-1|Location.X=1108|Location.Y=445|Color=8388608|FontID=1|IsHidden=T|Text=50V|Name=Voltage Rating (DC)
|RECORD=41|OwnerIndex=1892|IndexInSheet=4|OwnerPartId=-1|Location.X=1108|Location.Y=445|Color=8388608|FontID=1|IsHidden=T|Text=2|Name=Number of Terminations
|RECORD=41|OwnerIndex=1892|IndexInSheet=5|OwnerPartId=-1|Location.X=1108|Location.Y=445|Color=8388608|FontID=1|IsHidden=T|Text=SurfaceMount|Name=Mount
|RECORD=41|OwnerIndex=1892|IndexInSheet=6|OwnerPartId=-1|Location.X=1108|Location.Y=445|Color=8388608|FontID=1|IsHidden=T|Text=0.35mm|Name=Height
|RECORD=41|OwnerIndex=1892|IndexInSheet=7|OwnerPartId=-1|Location.X=1108|Location.Y=445|Color=8388608|FontID=1|IsHidden=T|Text=TapeandReel|Name=Packaging
|RECORD=41|OwnerIndex=1892|IndexInSheet=8|OwnerPartId=-1|Location.X=1108|Location.Y=445|Color=8388608|FontID=1|IsHidden=T|Text=Tin|Name=Contact Plating
|RECORD=41|OwnerIndex=1892|IndexInSheet=9|OwnerPartId=-1|Location.X=1108|Location.Y=445|Color=8388608|FontID=3|IsHidden=T|Text=http://www.panasonic.com/|Name=Manufacturer URL
|RECORD=41|OwnerIndex=1892|IndexInSheet=10|OwnerPartId=-1|Location.X=1108|Location.Y=445|Color=8388608|FontID=1|IsHidden=T|Text=ThickFilm|Name=Composition
|RECORD=41|OwnerIndex=1892|IndexInSheet=11|OwnerPartId=-1|Location.X=1108|Location.Y=445|Color=8388608|FontID=1|IsHidden=T|Text=155degC|Name=Max Operating Temperature
|RECORD=41|OwnerIndex=1892|IndexInSheet=12|OwnerPartId=-1|Location.X=1108|Location.Y=445|Color=8388608|FontID=1|IsHidden=T|Text=600ppm/??C|Name=Temperature Coefficient
|RECORD=41|OwnerIndex=1892|IndexInSheet=13|OwnerPartId=-1|Location.X=1108|Location.Y=445|Color=8388608|FontID=1|IsHidden=T|Text=NoSVHC|Name=REACH SVHC
|RECORD=41|OwnerIndex=1892|IndexInSheet=14|OwnerPartId=-1|Location.X=1108|Location.Y=445|Color=8388608|FontID=1|IsHidden=T|Text=0402|Name=Case/Package
|RECORD=41|OwnerIndex=1892|IndexInSheet=15|OwnerPartId=-1|Location.X=1108|Location.Y=445|Color=8388608|FontID=1|IsHidden=T|Text=100mW|Name=Max Power Dissipation
|RECORD=41|OwnerIndex=1892|IndexInSheet=16|OwnerPartId=-1|Location.X=1108|Location.Y=445|Color=8388608|FontID=1|IsHidden=T|Text=402|Name=Package Reference
|RECORD=41|OwnerIndex=1892|IndexInSheet=17|OwnerPartId=-1|Location.X=1108|Location.Y=445|Color=8388608|FontID=1|IsHidden=T|Text=0.5mm|Name=Depth
|RECORD=41|OwnerIndex=1892|IndexInSheet=18|OwnerPartId=-1|Location.X=1108|Location.Y=445|Color=8388608|FontID=1|IsHidden=T|Text=Panasonic|Name=Manufacturer
|RECORD=41|OwnerIndex=1892|IndexInSheet=19|OwnerPartId=-1|Location.X=1108|Location.Y=445|Color=8388608|FontID=1|IsHidden=T|Text=2-Pin Surface Mount Device, Body 1 x 0.5 mm|Name=Package Description
|RECORD=41|OwnerIndex=1892|IndexInSheet=20|OwnerPartId=-1|Location.X=1108|Location.Y=445|Color=8388608|FontID=3|IsHidden=T|Text=https://industrial.panasonic.com/cdbs/www-data/pdf/RDA0000/AOA0000C301.pdf|Name=Datasheet URL
|RECORD=41|OwnerIndex=1892|IndexInSheet=21|OwnerPartId=-1|Location.X=1108|Location.Y=445|Color=8388608|FontID=1|IsHidden=T|Text=True|Name=RoHSCompliant
|RECORD=41|OwnerIndex=1892|IndexInSheet=22|OwnerPartId=-1|Location.X=1108|Location.Y=445|Color=8388608|FontID=1|IsHidden=T|Text=0402|Name=Case Code (Imperial)
|RECORD=41|OwnerIndex=1892|IndexInSheet=23|OwnerPartId=-1|Location.X=1108|Location.Y=445|Color=8388608|FontID=1|IsHidden=T|Text=0mOhm|Name=Resistance
|RECORD=41|OwnerIndex=1892|IndexInSheet=24|OwnerPartId=-1|Location.X=1108|Location.Y=445|Color=8388608|FontID=1|IsHidden=T|Text=Not|Name=Military Standard
|RECORD=41|OwnerIndex=1892|IndexInSheet=25|OwnerPartId=-1|Location.X=1108|Location.Y=445|Color=8388608|FontID=1|IsHidden=T|Text=5%|Name=Tolerance
|RECORD=41|OwnerIndex=1892|IndexInSheet=26|OwnerPartId=-1|Location.X=1108|Location.Y=445|Color=8388608|FontID=1|IsHidden=T|Text=-55degC|Name=Min Operating Temperature
|RECORD=41|OwnerIndex=1892|IndexInSheet=27|OwnerPartId=-1|Location.X=1108|Location.Y=445|Color=8388608|FontID=1|IsHidden=T|Text=100mW|Name=Power Rating
|RECORD=41|OwnerIndex=1892|IndexInSheet=28|OwnerPartId=-1|Location.X=1108|Location.Y=445|Color=8388608|FontID=1|IsHidden=T|Text=03/2015|Name=Datasheet Version
|RECORD=41|OwnerIndex=1892|IndexInSheet=29|OwnerPartId=-1|Location.X=1108|Location.Y=445|Color=8388608|FontID=1|IsHidden=T|Text=1mm|Name=Length
|RECORD=41|OwnerIndex=1892|IndexInSheet=30|OwnerPartId=-1|Location.X=1108|Location.Y=445|Color=8388608|FontID=1|IsHidden=T|Text=1005|Name=Case Code (Metric)
|RECORD=41|OwnerIndex=1892|IndexInSheet=31|OwnerPartId=-1|Location.X=1108|Location.Y=445|Color=8388608|FontID=1|IsHidden=T|Text=SMD/SMT|Name=Termination
|RECORD=41|OwnerIndex=1892|IndexInSheet=32|OwnerPartId=-1|Location.X=1108|Location.Y=445|Color=8388608|FontID=1|IsHidden=T|Text=SurfaceMount|Name=Mounting Technology
|RECORD=41|OwnerIndex=1892|IndexInSheet=33|OwnerPartId=-1|Location.X=1108|Location.Y=445|Color=8388608|FontID=1|IsHidden=T|Text=50V|Name=Voltage Rating
|RECORD=41|OwnerIndex=1892|IndexInSheet=34|OwnerPartId=-1|Location.X=1108|Location.Y=445|Color=8388608|FontID=1|IsHidden=T|Text=0.02inch|Name=Width
|RECORD=41|OwnerIndex=1892|IndexInSheet=35|OwnerPartId=-1|Location.X=1108|Location.Y=445|Color=8388608|FontID=1|IsHidden=T|Text=1|Name=Package Quantity
|RECORD=41|OwnerIndex=1892|IndexInSheet=36|OwnerPartId=-1|Location.X=1108|Location.Y=445|Color=8388608|FontID=1|IsHidden=T|Text=LeadFree|Name=Lead Free
|RECORD=41|OwnerIndex=1892|IndexInSheet=37|OwnerPartId=-1|Location.X=1108|Location.Y=445|Color=8388608|FontID=1|IsHidden=T|Text=No|Name=Radiation Hardening
|RECORD=34|OwnerIndex=1892|IndexInSheet=-1|OwnerPartId=-1|Location.X=1100|Location.Y=430|Color=8388608|FontID=1|Text=R139|Name=Designator|ReadOnlyState=1
|RECORD=41|OwnerIndex=1892|IndexInSheet=-1|OwnerPartId=-1|Location.X=1140|Location.Y=430|Color=8388608|FontID=1|Text=0_1%_0402|Name=Comment
|RECORD=44|OwnerIndex=1892
|RECORD=45|OwnerIndex=1935|IndexInSheet=-1|Description=Chip Resistor, 2-Leads, Body 1.05x0.55mm, IPC High Density|UseComponentLibrary=T|ModelName=RESC1005X40X25LL05T05|ModelType=PCBLIB|DatafileCount=1|ModelDatafileEntity0=RESC1005X40X25LL05T05|ModelDatafileKind0=PCBLib|IsCurrent=T|DatalinksLocked=T|DatabaseDatalinksLocked=T
|RECORD=46|OwnerIndex=1936
|RECORD=48|OwnerIndex=1936
|RECORD=41|OwnerIndex=1938|IndexInSheet=-1|OwnerPartId=-1|Color=8388608|FontID=1|IsHidden=T|Text=2D|Name=Available Preview Images
|RECORD=45|OwnerIndex=1935|IndexInSheet=-1|Description=Chip Resistor, 2-Leads, Body 1.05x0.55mm, IPC Low Density|UseComponentLibrary=T|ModelName=RESC1005X40X25ML05T05|ModelType=PCBLIB|DatafileCount=1|ModelDatafileEntity0=RESC1005X40X25ML05T05|ModelDatafileKind0=PCBLib|DatalinksLocked=T|DatabaseDatalinksLocked=T
|RECORD=46|OwnerIndex=1940
|RECORD=48|OwnerIndex=1940
|RECORD=41|OwnerIndex=1942|IndexInSheet=-1|OwnerPartId=-1|Color=8388608|FontID=1|IsHidden=T|Text=2D|Name=Available Preview Images
|RECORD=45|OwnerIndex=1935|IndexInSheet=-1|Description=Chip Resistor, 2-Leads, Body 1.05x0.55mm, IPC Medium Density|UseComponentLibrary=T|ModelName=RESC1005X40X25NL05T05|ModelType=PCBLIB|DatafileCount=1|ModelDatafileEntity0=RESC1005X40X25NL05T05|ModelDatafileKind0=PCBLib|DatalinksLocked=T|DatabaseDatalinksLocked=T
|RECORD=46|OwnerIndex=1944
|RECORD=48|OwnerIndex=1944
|RECORD=41|OwnerIndex=1946|IndexInSheet=-1|OwnerPartId=-1|Color=8388608|FontID=1|IsHidden=T|Text=2D|Name=Available Preview Images
|RECORD=17|IndexInSheet=110|OwnerPartId=-1|ShowNetName=T|Location.X=1200|Location.Y=430|Color=255|FontID=1|Text=M2_GPS2_TP1|IsCrossSheetConnector=T
|RECORD=27|IndexInSheet=111|OwnerPartId=-1|LineWidth=1|Color=8388608|LocationCount=2|X1=770|Y1=760|X2=790|Y2=760
|RECORD=27|IndexInSheet=112|OwnerPartId=-1|LineWidth=1|Color=8388608|LocationCount=2|X1=770|Y1=700|X2=790|Y2=700
|RECORD=27|IndexInSheet=113|OwnerPartId=-1|LineWidth=1|Color=8388608|LocationCount=2|X1=770|Y1=620|X2=790|Y2=620
|RECORD=27|IndexInSheet=114|OwnerPartId=-1|LineWidth=1|Color=8388608|LocationCount=2|X1=770|Y1=560|X2=790|Y2=560
|RECORD=27|IndexInSheet=115|OwnerPartId=-1|LineWidth=1|Color=8388608|LocationCount=2|X1=770|Y1=500|X2=790|Y2=500
|RECORD=27|IndexInSheet=116|OwnerPartId=-1|LineWidth=1|Color=8388608|LocationCount=2|X1=770|Y1=440|X2=790|Y2=440
|RECORD=27|IndexInSheet=117|OwnerPartId=-1|LineWidth=1|Color=8388608|LocationCount=2|X1=770|Y1=380|X2=790|Y2=380
|RECORD=27|IndexInSheet=118|OwnerPartId=-1|LineWidth=1|Color=8388608|LocationCount=2|X1=770|Y1=320|X2=790|Y2=320
|RECORD=27|IndexInSheet=119|OwnerPartId=-1|LineWidth=1|Color=8388608|LocationCount=2|X1=770|Y1=180|X2=790|Y2=180
|RECORD=27|IndexInSheet=120|OwnerPartId=-1|LineWidth=1|Color=8388608|LocationCount=2|X1=770|Y1=160|X2=790|Y2=160
|RECORD=27|IndexInSheet=121|OwnerPartId=-1|LineWidth=1|Color=8388608|LocationCount=3|X1=1090|Y1=810|X2=1090|Y2=790|X3=1060|Y3=790
|RECORD=27|IndexInSheet=122|OwnerPartId=-1|LineWidth=1|Color=8388608|LocationCount=3|X1=1060|Y1=770|X2=1090|Y2=770|X3=1090|Y3=790
|RECORD=27|IndexInSheet=123|OwnerPartId=-1|LineWidth=1|Color=8388608|LocationCount=3|X1=1060|Y1=170|X2=1090|Y2=170|X3=1090|Y3=190
|RECORD=27|IndexInSheet=124|OwnerPartId=-1|LineWidth=1|Color=8388608|LocationCount=3|X1=1060|Y1=150|X2=1090|Y2=150|X3=1090|Y3=170
|RECORD=27|IndexInSheet=125|OwnerPartId=-1|LineWidth=1|Color=8388608|LocationCount=3|X1=1060|Y1=130|X2=1090|Y2=130|X3=1090|Y3=110
|RECORD=27|IndexInSheet=126|OwnerPartId=-1|LineWidth=1|Color=8388608|LocationCount=2|X1=770|Y1=120|X2=790|Y2=120
|RECORD=27|IndexInSheet=127|OwnerPartId=-1|LineWidth=1|Color=8388608|LocationCount=2|X1=1060|Y1=690|X2=1120|Y2=690
|RECORD=27|IndexInSheet=128|OwnerPartId=-1|LineWidth=1|Color=8388608|LocationCount=2|X1=1060|Y1=670|X2=1120|Y2=670
|RECORD=27|IndexInSheet=129|OwnerPartId=-1|LineWidth=1|Color=8388608|LocationCount=2|X1=770|Y1=540|X2=820|Y2=540
|RECORD=27|IndexInSheet=130|OwnerPartId=-1|LineWidth=1|Color=8388608|LocationCount=2|X1=860|Y1=540|X2=910|Y2=540
|RECORD=27|IndexInSheet=131|OwnerPartId=-1|LineWidth=1|Color=8388608|LocationCount=2|X1=1060|Y1=430|X2=1110|Y2=430
|RECORD=27|IndexInSheet=132|OwnerPartId=-1|LineWidth=1|Color=8388608|LocationCount=2|X1=1150|Y1=430|X2=1200|Y2=430
|RECORD=27|IndexInSheet=133|OwnerPartId=-1|LineWidth=1|Color=8388608|LocationCount=2|X1=1060|Y1=390|X2=1140|Y2=390
|RECORD=27|IndexInSheet=134|OwnerPartId=-1|LineWidth=1|Color=8388608|LocationCount=2|X1=770|Y1=220|X2=830|Y2=220
|RECORD=27|IndexInSheet=135|OwnerPartId=-1|LineWidth=1|Color=8388608|LocationCount=2|X1=1060|Y1=270|X2=1140|Y2=270
|RECORD=27|IndexInSheet=136|OwnerPartId=-1|LineWidth=1|Color=8388608|LocationCount=2|X1=1060|Y1=250|X2=1140|Y2=250
|RECORD=27|IndexInSheet=137|OwnerPartId=-1|LineWidth=1|Color=8388608|LocationCount=2|X1=1060|Y1=410|X2=1140|Y2=410
|RECORD=4|IndexInSheet=138|OwnerPartId=-1|Location.X=1230|Location.Y=470|Color=8388608|FontID=1|Text=I2C & IRQ
|RECORD=1|LibReference=RES|PartCount=2|DisplayModeCount=2|IndexInSheet=139|OwnerPartId=-1|Location.X=1100|Location.Y=510|Orientation=1|CurrentPartId=1|SourceLibraryName=Altium Content Vault|TargetFileName=*|AreaColor=11599871|Color=128|PartIDLocked=F|DesignItemId=CMP-2002-05217-1|AllPinCount=2
|RECORD=2|OwnerIndex=1977|OwnerPartId=1|OwnerPartDisplayMode=1|FormalType=1|Electrical=4|PinConglomerate=33|PinLength=10|Location.X=1110|Location.Y=530|Name=2|Designator=2|PinPropagationDelay=0.000000E+000
|RECORD=2|OwnerIndex=1977|OwnerPartId=1|OwnerPartDisplayMode=1|FormalType=1|Electrical=4|PinConglomerate=35|PinLength=10|Location.X=1110|Location.Y=510|Name=1|Designator=1|PinPropagationDelay=0.000000E+000
|RECORD=14|OwnerIndex=1977|IsNotAccesible=T|IndexInSheet=2|OwnerPartId=1|OwnerPartDisplayMode=1|Location.X=1106|Location.Y=510|Corner.X=1114|Corner.Y=530|LineWidth=1|Color=16711680|AreaColor=11599871
|RECORD=2|OwnerIndex=1977|OwnerPartId=1|FormalType=1|Electrical=4|PinConglomerate=33|PinLength=10|Location.X=1110|Location.Y=530|Name=2|Designator=2|PinPropagationDelay=0.000000E+000
|RECORD=2|OwnerIndex=1977|OwnerPartId=1|FormalType=1|Electrical=4|PinConglomerate=35|PinLength=10|Location.X=1110|Location.Y=510|Name=1|Designator=1|PinPropagationDelay=0.000000E+000
|RECORD=6|OwnerIndex=1977|IsNotAccesible=T|IndexInSheet=5|OwnerPartId=1|LineWidth=1|Color=16711680|LocationCount=10|X1=1110|Y1=530|X2=1110|Y2=526|X3=1112|Y3=525|X4=1108|Y4=523|X5=1112|Y5=521|X6=1108|Y6=519|X7=1112|Y7=517|X8=1108|Y8=515|X9=1110|Y9=514|X10=1110|Y10=510
|RECORD=41|OwnerIndex=1977|IndexInSheet=6|OwnerPartId=-1|Location.X=1107|Location.Y=542|Color=8388608|FontID=1|IsHidden=T|Text=Bourns|Name=Manufacturer
|RECORD=41|OwnerIndex=1977|IndexInSheet=7|OwnerPartId=-1|Location.X=1107|Location.Y=542|Color=8388608|FontID=1|IsHidden=T|Text=CR0402-FX-4701GLF|Name=Part Number
|RECORD=34|OwnerIndex=1977|IndexInSheet=-1|OwnerPartId=-1|Location.X=1110|Location.Y=500|Orientation=1|Color=8388608|FontID=2|Text=R135|Name=Designator|ReadOnlyState=1
|RECORD=41|OwnerIndex=1977|IndexInSheet=-1|OwnerPartId=-1|Location.X=1120|Location.Y=500|Orientation=1|Color=8388608|FontID=2|Text=4.7K_1%_0402|Name=Comment
|RECORD=44|OwnerIndex=1977
|RECORD=45|OwnerIndex=1992|IndexInSheet=-1|Description=Chip Resistor, 2-Leads, Body 1.00x0.50mm, IPC Medium Density|UseComponentLibrary=T|ModelName=RESC1005X40X25NL10T10|ModelType=PCBLIB|DatafileCount=1|ModelDatafileEntity0=RESC1005X40X25NL10T10|ModelDatafileKind0=PCBLib|IsCurrent=T|DatalinksLocked=T|DatabaseDatalinksLocked=T
|RECORD=46|OwnerIndex=1993
|RECORD=48|OwnerIndex=1993
|RECORD=41|OwnerIndex=1995|IndexInSheet=-1|OwnerPartId=-1|Color=8388608|FontID=1|IsHidden=T|Text=2D|Name=Available Preview Images
|RECORD=45|OwnerIndex=1992|IndexInSheet=-1|Description=Chip Resistor, 2-Leads, Body 1.00x0.50mm, IPC High Density|UseComponentLibrary=T|ModelName=RESC1005X40X25LL10T10|ModelType=PCBLIB|DatafileCount=1|ModelDatafileEntity0=RESC1005X40X25LL10T10|ModelDatafileKind0=PCBLib|DatalinksLocked=T|DatabaseDatalinksLocked=T
|RECORD=46|OwnerIndex=1997
|RECORD=48|OwnerIndex=1997
|RECORD=41|OwnerIndex=1999|IndexInSheet=-1|OwnerPartId=-1|Color=8388608|FontID=1|IsHidden=T|Text=2D|Name=Available Preview Images
|RECORD=45|OwnerIndex=1992|IndexInSheet=-1|Description=Chip Resistor, 2-Leads, Body 1.00x0.50mm, IPC Low Density|UseComponentLibrary=T|ModelName=RESC1005X40X25ML10T10|ModelType=PCBLIB|DatafileCount=1|ModelDatafileEntity0=RESC1005X40X25ML10T10|ModelDatafileKind0=PCBLib|DatalinksLocked=T|DatabaseDatalinksLocked=T
|RECORD=46|OwnerIndex=2001
|RECORD=48|OwnerIndex=2001
|RECORD=41|OwnerIndex=2003|IndexInSheet=-1|OwnerPartId=-1|Color=8388608|FontID=1|IsHidden=T|Text=2D|Name=Available Preview Images
|RECORD=1|LibReference=RES|PartCount=2|DisplayModeCount=2|IndexInSheet=140|OwnerPartId=-1|Location.X=1120|Location.Y=510|Orientation=1|CurrentPartId=1|SourceLibraryName=Altium Content Vault|TargetFileName=*|AreaColor=11599871|Color=128|PartIDLocked=F|DesignItemId=CMP-2002-05217-1|AllPinCount=2
|RECORD=2|OwnerIndex=2005|OwnerPartId=1|OwnerPartDisplayMode=1|FormalType=1|Electrical=4|PinConglomerate=33|PinLength=10|Location.X=1130|Location.Y=530|Name=2|Designator=2|PinPropagationDelay=0.000000E+000
|RECORD=2|OwnerIndex=2005|OwnerPartId=1|OwnerPartDisplayMode=1|FormalType=1|Electrical=4|PinConglomerate=35|PinLength=10|Location.X=1130|Location.Y=510|Name=1|Designator=1|PinPropagationDelay=0.000000E+000
|RECORD=14|OwnerIndex=2005|IsNotAccesible=T|IndexInSheet=2|OwnerPartId=1|OwnerPartDisplayMode=1|Location.X=1126|Location.Y=510|Corner.X=1134|Corner.Y=530|LineWidth=1|Color=16711680|AreaColor=11599871
|RECORD=2|OwnerIndex=2005|OwnerPartId=1|FormalType=1|Electrical=4|PinConglomerate=33|PinLength=10|Location.X=1130|Location.Y=530|Name=2|Designator=2|PinPropagationDelay=0.000000E+000
|RECORD=2|OwnerIndex=2005|OwnerPartId=1|FormalType=1|Electrical=4|PinConglomerate=35|PinLength=10|Location.X=1130|Location.Y=510|Name=1|Designator=1|PinPropagationDelay=0.000000E+000
|RECORD=6|OwnerIndex=2005|IsNotAccesible=T|IndexInSheet=5|OwnerPartId=1|LineWidth=1|Color=16711680|LocationCount=10|X1=1130|Y1=530|X2=1130|Y2=526|X3=1132|Y3=525|X4=1128|Y4=523|X5=1132|Y5=521|X6=1128|Y6=519|X7=1132|Y7=517|X8=1128|Y8=515|X9=1130|Y9=514|X10=1130|Y10=510
|RECORD=41|OwnerIndex=2005|IndexInSheet=6|OwnerPartId=-1|Location.X=1127|Location.Y=542|Color=8388608|FontID=1|IsHidden=T|Text=Bourns|Name=Manufacturer
|RECORD=41|OwnerIndex=2005|IndexInSheet=7|OwnerPartId=-1|Location.X=1127|Location.Y=542|Color=8388608|FontID=1|IsHidden=T|Text=CR0402-FX-4701GLF|Name=Part Number
|RECORD=34|OwnerIndex=2005|IndexInSheet=-1|OwnerPartId=-1|Location.X=1130|Location.Y=500|Orientation=1|Color=8388608|FontID=2|Text=R136|Name=Designator|ReadOnlyState=1
|RECORD=41|OwnerIndex=2005|IndexInSheet=-1|OwnerPartId=-1|Location.X=1140|Location.Y=500|Orientation=1|Color=8388608|FontID=2|Text=4.7K_1%_0402|Name=Comment
|RECORD=44|OwnerIndex=2005
|RECORD=45|OwnerIndex=2020|IndexInSheet=-1|Description=Chip Resistor, 2-Leads, Body 1.00x0.50mm, IPC Medium Density|UseComponentLibrary=T|ModelName=RESC1005X40X25NL10T10|ModelType=PCBLIB|DatafileCount=1|ModelDatafileEntity0=RESC1005X40X25NL10T10|ModelDatafileKind0=PCBLib|IsCurrent=T|DatalinksLocked=T|DatabaseDatalinksLocked=T
|RECORD=46|OwnerIndex=2021
|RECORD=48|OwnerIndex=2021
|RECORD=41|OwnerIndex=2023|IndexInSheet=-1|OwnerPartId=-1|Color=8388608|FontID=1|IsHidden=T|Text=2D|Name=Available Preview Images
|RECORD=45|OwnerIndex=2020|IndexInSheet=-1|Description=Chip Resistor, 2-Leads, Body 1.00x0.50mm, IPC High Density|UseComponentLibrary=T|ModelName=RESC1005X40X25LL10T10|ModelType=PCBLIB|DatafileCount=1|ModelDatafileEntity0=RESC1005X40X25LL10T10|ModelDatafileKind0=PCBLib|DatalinksLocked=T|DatabaseDatalinksLocked=T
|RECORD=46|OwnerIndex=2025
|RECORD=48|OwnerIndex=2025
|RECORD=41|OwnerIndex=2027|IndexInSheet=-1|OwnerPartId=-1|Color=8388608|FontID=1|IsHidden=T|Text=2D|Name=Available Preview Images
|RECORD=45|OwnerIndex=2020|IndexInSheet=-1|Description=Chip Resistor, 2-Leads, Body 1.00x0.50mm, IPC Low Density|UseComponentLibrary=T|ModelName=RESC1005X40X25ML10T10|ModelType=PCBLIB|DatafileCount=1|ModelDatafileEntity0=RESC1005X40X25ML10T10|ModelDatafileKind0=PCBLib|DatalinksLocked=T|DatabaseDatalinksLocked=T
|RECORD=46|OwnerIndex=2029
|RECORD=48|OwnerIndex=2029
|RECORD=41|OwnerIndex=2031|IndexInSheet=-1|OwnerPartId=-1|Color=8388608|FontID=1|IsHidden=T|Text=2D|Name=Available Preview Images
|RECORD=1|LibReference=RES|PartCount=2|DisplayModeCount=2|IndexInSheet=141|OwnerPartId=-1|Location.X=1140|Location.Y=510|Orientation=1|CurrentPartId=1|SourceLibraryName=Altium Content Vault|TargetFileName=*|AreaColor=11599871|Color=128|PartIDLocked=F|DesignItemId=CMP-2002-05217-1|AllPinCount=2
|RECORD=2|OwnerIndex=2033|OwnerPartId=1|OwnerPartDisplayMode=1|FormalType=1|Electrical=4|PinConglomerate=33|PinLength=10|Location.X=1150|Location.Y=530|Name=2|Designator=2|PinPropagationDelay=0.000000E+000
|RECORD=2|OwnerIndex=2033|OwnerPartId=1|OwnerPartDisplayMode=1|FormalType=1|Electrical=4|PinConglomerate=35|PinLength=10|Location.X=1150|Location.Y=510|Name=1|Designator=1|PinPropagationDelay=0.000000E+000
|RECORD=14|OwnerIndex=2033|IsNotAccesible=T|IndexInSheet=2|OwnerPartId=1|OwnerPartDisplayMode=1|Location.X=1146|Location.Y=510|Corner.X=1154|Corner.Y=530|LineWidth=1|Color=16711680|AreaColor=11599871
|RECORD=2|OwnerIndex=2033|OwnerPartId=1|FormalType=1|Electrical=4|PinConglomerate=33|PinLength=10|Location.X=1150|Location.Y=530|Name=2|Designator=2|PinPropagationDelay=0.000000E+000
|RECORD=2|OwnerIndex=2033|OwnerPartId=1|FormalType=1|Electrical=4|PinConglomerate=35|PinLength=10|Location.X=1150|Location.Y=510|Name=1|Designator=1|PinPropagationDelay=0.000000E+000
|RECORD=6|OwnerIndex=2033|IsNotAccesible=T|IndexInSheet=5|OwnerPartId=1|LineWidth=1|Color=16711680|LocationCount=10|X1=1150|Y1=530|X2=1150|Y2=526|X3=1152|Y3=525|X4=1148|Y4=523|X5=1152|Y5=521|X6=1148|Y6=519|X7=1152|Y7=517|X8=1148|Y8=515|X9=1150|Y9=514|X10=1150|Y10=510
|RECORD=41|OwnerIndex=2033|IndexInSheet=6|OwnerPartId=-1|Location.X=1147|Location.Y=542|Color=8388608|FontID=1|IsHidden=T|Text=Bourns|Name=Manufacturer
|RECORD=41|OwnerIndex=2033|IndexInSheet=7|OwnerPartId=-1|Location.X=1147|Location.Y=542|Color=8388608|FontID=1|IsHidden=T|Text=CR0402-FX-4701GLF|Name=Part Number
|RECORD=34|OwnerIndex=2033|IndexInSheet=-1|OwnerPartId=-1|Location.X=1150|Location.Y=500|Orientation=1|Color=8388608|FontID=2|Text=R137|Name=Designator|ReadOnlyState=1
|RECORD=41|OwnerIndex=2033|IndexInSheet=-1|OwnerPartId=-1|Location.X=1160|Location.Y=500|Orientation=1|Color=8388608|FontID=2|Text=4.7K_1%_0402|Name=Comment
|RECORD=44|OwnerIndex=2033
|RECORD=45|OwnerIndex=2048|IndexInSheet=-1|Description=Chip Resistor, 2-Leads, Body 1.00x0.50mm, IPC Medium Density|UseComponentLibrary=T|ModelName=RESC1005X40X25NL10T10|ModelType=PCBLIB|DatafileCount=1|ModelDatafileEntity0=RESC1005X40X25NL10T10|ModelDatafileKind0=PCBLib|IsCurrent=T|DatalinksLocked=T|DatabaseDatalinksLocked=T
|RECORD=46|OwnerIndex=2049
|RECORD=48|OwnerIndex=2049
|RECORD=41|OwnerIndex=2051|IndexInSheet=-1|OwnerPartId=-1|Color=8388608|FontID=1|IsHidden=T|Text=2D|Name=Available Preview Images
|RECORD=45|OwnerIndex=2048|IndexInSheet=-1|Description=Chip Resistor, 2-Leads, Body 1.00x0.50mm, IPC High Density|UseComponentLibrary=T|ModelName=RESC1005X40X25LL10T10|ModelType=PCBLIB|DatafileCount=1|ModelDatafileEntity0=RESC1005X40X25LL10T10|ModelDatafileKind0=PCBLib|DatalinksLocked=T|DatabaseDatalinksLocked=T
|RECORD=46|OwnerIndex=2053
|RECORD=48|OwnerIndex=2053
|RECORD=41|OwnerIndex=2055|IndexInSheet=-1|OwnerPartId=-1|Color=8388608|FontID=1|IsHidden=T|Text=2D|Name=Available Preview Images
|RECORD=45|OwnerIndex=2048|IndexInSheet=-1|Description=Chip Resistor, 2-Leads, Body 1.00x0.50mm, IPC Low Density|UseComponentLibrary=T|ModelName=RESC1005X40X25ML10T10|ModelType=PCBLIB|DatafileCount=1|ModelDatafileEntity0=RESC1005X40X25ML10T10|ModelDatafileKind0=PCBLib|DatalinksLocked=T|DatabaseDatalinksLocked=T
|RECORD=46|OwnerIndex=2057
|RECORD=48|OwnerIndex=2057
|RECORD=41|OwnerIndex=2059|IndexInSheet=-1|OwnerPartId=-1|Color=8388608|FontID=1|IsHidden=T|Text=2D|Name=Available Preview Images
|RECORD=27|IndexInSheet=142|OwnerPartId=-1|LineWidth=1|Color=8388608|LocationCount=3|X1=1110|Y1=540|X2=1110|Y2=560|X3=1090|Y3=560
|RECORD=27|IndexInSheet=143|OwnerPartId=-1|LineWidth=1|Color=8388608|LocationCount=3|X1=1110|Y1=560|X2=1130|Y2=560|X3=1130|Y3=540
|RECORD=27|IndexInSheet=144|OwnerPartId=-1|LineWidth=1|Color=8388608|LocationCount=3|X1=1130|Y1=560|X2=1150|Y2=560|X3=1150|Y3=540
|RECORD=27|IndexInSheet=145|OwnerPartId=-1|LineWidth=1|Color=8388608|LocationCount=2|X1=1150|Y1=500|X2=1150|Y2=450
|RECORD=27|IndexInSheet=146|OwnerPartId=-1|LineWidth=1|Color=8388608|LocationCount=2|X1=1130|Y1=500|X2=1130|Y2=470
|RECORD=27|IndexInSheet=147|OwnerPartId=-1|LineWidth=1|Color=8388608|LocationCount=2|X1=1110|Y1=500|X2=1110|Y2=490
|RECORD=27|IndexInSheet=148|OwnerPartId=-1|LineWidth=1|Color=8388608|LocationCount=14|X1=790|Y1=100|X2=790|Y2=120|X3=790|Y3=160|X4=790|Y4=180|X5=790|Y5=320|X6=790|Y6=380|X7=790|Y7=440|X8=790|Y8=500|X9=790|Y9=560|X10=790|Y10=620|X11=790|Y11=700|X12=790|Y12=760|X13=790|Y13=780|X14=770|Y14=780
|RECORD=27|IndexInSheet=149|OwnerPartId=-1|LineWidth=1|Color=8388608|LocationCount=5|X1=1090|Y1=770|X2=1090|Y2=560|X3=1090|Y3=200|X4=1090|Y4=190|X5=1060|Y5=190
|RECORD=27|IndexInSheet=150|OwnerPartId=-1|LineWidth=1|Color=8388608|LocationCount=3|X1=1060|Y1=450|X2=1150|Y2=450|X3=1160|Y3=450
|RECORD=27|IndexInSheet=151|OwnerPartId=-1|LineWidth=1|Color=8388608|LocationCount=3|X1=1060|Y1=470|X2=1130|Y2=470|X3=1160|Y3=470
|RECORD=27|IndexInSheet=152|OwnerPartId=-1|LineWidth=1|Color=8388608|LocationCount=3|X1=1060|Y1=490|X2=1110|Y2=490|X3=1160|Y3=490
|RECORD=1|LibReference=b4654b650e69147ec39a6b967a45e02|ComponentDescription=General Purpose Ceramic Capacitor, 0402, 100nF, 10%, X7R, 15%, 25V|PartCount=2|DisplayModeCount=1|IndexInSheet=153|OwnerPartId=-1|Location.X=490|Location.Y=170|CurrentPartId=1|LibraryPath=*|SourceLibraryName=Altium Content Vault|TargetFileName=*|AreaColor=11599871|Color=128|PartIDLocked=T|DesignItemId=CMP-2008-02519-2|AllPinCount=2
|RECORD=2|OwnerIndex=2072|OwnerPartId=1|Electrical=4|PinConglomerate=49|PinLength=7|Location.X=490|Location.Y=163|Name=1|Designator=1|PinPropagationDelay=0.000000E+000
|RECORD=2|OwnerIndex=2072|OwnerPartId=1|Electrical=4|PinConglomerate=51|PinLength=6|Location.X=490|Location.Y=156|Name=2|Designator=2|PinPropagationDelay=0.000000E+000
|RECORD=13|OwnerIndex=2072|IsNotAccesible=T|IndexInSheet=2|OwnerPartId=1|Location.X=500|Location.Y=163|Corner.X=480|Corner.Y=163|LineWidth=1|Color=16711680
|RECORD=13|OwnerIndex=2072|IsNotAccesible=T|IndexInSheet=3|OwnerPartId=1|Location.X=500|Location.Y=157|Corner.X=480|Corner.Y=157|LineWidth=1|Color=16711680
|RECORD=13|OwnerIndex=2072|IsNotAccesible=T|IndexInSheet=4|OwnerPartId=1|Location.X=490|Location.Y=163|Corner.X=490|Corner.Y=166|LineWidth=1|Color=16711680
|RECORD=13|OwnerIndex=2072|IsNotAccesible=T|IndexInSheet=5|OwnerPartId=1|Location.X=490|Location.Y=156|Corner.X=490|Corner.Y=155|LineWidth=1|Color=16711680
|RECORD=41|OwnerIndex=2072|IndexInSheet=6|OwnerPartId=-1|Location.X=479|Location.Y=172|Color=8388608|FontID=1|IsHidden=T|Text=1|Name=Package Quantity
|RECORD=41|OwnerIndex=2072|IndexInSheet=7|OwnerPartId=-1|Location.X=479|Location.Y=172|Color=8388608|FontID=1|IsHidden=T|Text=100nF|Name=Capacitance
|RECORD=41|OwnerIndex=2072|IndexInSheet=8|OwnerPartId=-1|Location.X=479|Location.Y=172|Color=8388608|FontID=1|IsHidden=T|Text=-55°C|Name=Min Operating Temperature
|RECORD=41|OwnerIndex=2072|IndexInSheet=9|OwnerPartId=-1|Location.X=479|Location.Y=172|Color=8388608|FontID=1|IsHidden=T|Text=25V|Name=Voltage
|RECORD=41|OwnerIndex=2072|IndexInSheet=10|OwnerPartId=-1|Location.X=479|Location.Y=172|Color=8388608|FontID=1|IsHidden=T|Text=25V|Name=Voltage Rating
|RECORD=41|OwnerIndex=2072|IndexInSheet=11|OwnerPartId=-1|Location.X=479|Location.Y=172|Color=8388608|FontID=1|IsHidden=T|Text=Flat|Name=Construction
|RECORD=41|OwnerIndex=2072|IndexInSheet=12|OwnerPartId=-1|Location.X=479|Location.Y=172|Color=8388608|FontID=1|IsHidden=T|Text=125°C|Name=Max Operating Temperature
|RECORD=41|OwnerIndex=2072|IndexInSheet=13|OwnerPartId=-1|Location.X=479|Location.Y=172|Color=8388608|FontID=1|IsHidden=T|Text=No|Name=Radiation Hardening
|RECORD=41|OwnerIndex=2072|IndexInSheet=14|OwnerPartId=-1|Location.X=479|Location.Y=172|Color=8388608|FontID=1|IsHidden=T|Text=0.5mm|Name=Depth
|RECORD=41|OwnerIndex=2072|IndexInSheet=15|OwnerPartId=-1|Location.X=479|Location.Y=172|Color=8388608|FontID=1|IsHidden=T|Text=0.022inch|Name=Thickness
|RECORD=41|OwnerIndex=2072|IndexInSheet=16|OwnerPartId=-1|Location.X=479|Location.Y=172|Color=8388608|FontID=1|IsHidden=T|Text=25V|Name=Voltage Rating (DC)
|RECORD=41|OwnerIndex=2072|IndexInSheet=17|OwnerPartId=-1|Location.X=479|Location.Y=172|Color=8388608|FontID=1|IsHidden=T|Text=2|Name=Number of Pins
|RECORD=41|OwnerIndex=2072|IndexInSheet=18|OwnerPartId=-1|Location.X=479|Location.Y=172|Color=8388608|FontID=1|IsHidden=T|Text=Lead Free|Name=Lead Free
|RECORD=41|OwnerIndex=2072|IndexInSheet=19|OwnerPartId=-1|Location.X=479|Location.Y=172|Color=8388608|FontID=1|IsHidden=T|Text=-|Name=Series
|RECORD=41|OwnerIndex=2072|IndexInSheet=20|OwnerPartId=-1|Location.X=479|Location.Y=172|Color=8388608|FontID=1|IsHidden=T|Text=No SVHC|Name=REACH SVHC
|RECORD=41|OwnerIndex=2072|IndexInSheet=21|OwnerPartId=-1|Location.X=479|Location.Y=172|Color=8388608|FontID=1|IsHidden=T|Text=1mm|Name=Length
|RECORD=41|OwnerIndex=2072|IndexInSheet=22|OwnerPartId=-1|Location.X=479|Location.Y=172|Color=8388608|FontID=1|IsHidden=T|Text=X7R|Name=Dielectric
|RECORD=41|OwnerIndex=2072|IndexInSheet=23|OwnerPartId=-1|Location.X=479|Location.Y=172|Color=8388608|FontID=1|IsHidden=T|Text=Yes|Name=RoHS Compliant
|RECORD=41|OwnerIndex=2072|IndexInSheet=24|OwnerPartId=-1|Location.X=479|Location.Y=172|Color=8388608|FontID=1|IsHidden=T|Text=Surface Mount|Name=Mount
|RECORD=41|OwnerIndex=2072|IndexInSheet=25|OwnerPartId=-1|Location.X=479|Location.Y=172|Color=8388608|FontID=1|IsHidden=T|Text=Tape and Reel|Name=Packaging
|RECORD=41|OwnerIndex=2072|IndexInSheet=26|OwnerPartId=-1|Location.X=479|Location.Y=172|Color=8388608|FontID=1|IsHidden=T|Text=0402|Name=Case/Package
|RECORD=41|OwnerIndex=2072|IndexInSheet=27|OwnerPartId=-1|Location.X=479|Location.Y=172|Color=8388608|FontID=1|IsHidden=T|Text=0402|Name=Case Code (Imperial)
|RECORD=41|OwnerIndex=2072|IndexInSheet=28|OwnerPartId=-1|Location.X=479|Location.Y=172|Color=8388608|FontID=1|IsHidden=T|Text=SMD/SMT|Name=Termination
|RECORD=41|OwnerIndex=2072|IndexInSheet=29|OwnerPartId=-1|Location.X=479|Location.Y=172|Color=8388608|FontID=1|IsHidden=T|Text=0.02inch|Name=Width
|RECORD=41|OwnerIndex=2072|IndexInSheet=30|OwnerPartId=-1|Location.X=479|Location.Y=172|Color=8388608|FontID=1|IsHidden=T|Text=1005|Name=Case Code (Metric)
|RECORD=41|OwnerIndex=2072|IndexInSheet=31|OwnerPartId=-1|Location.X=479|Location.Y=172|Color=8388608|FontID=1|IsHidden=T|Text=10%|Name=Tolerance
|RECORD=34|OwnerIndex=2072|IndexInSheet=-1|OwnerPartId=-1|Location.X=480|Location.Y=150|Orientation=1|Color=8388608|FontID=2|Text=C74|Name=Designator|ReadOnlyState=1
|RECORD=41|OwnerIndex=2072|IndexInSheet=-1|OwnerPartId=1|Location.X=510|Location.Y=135|Orientation=1|Color=8388608|FontID=2|Text=0.1uF_25V_0402|Name=Comment
|RECORD=44|OwnerIndex=2072
|RECORD=45|OwnerIndex=2109|IndexInSheet=-1|UseComponentLibrary=T|ModelName=FP-0402-L_1_0_1-W_0_5_0_1-IPC_C|ModelType=PCBLIB|DatafileCount=1|ModelDatafileEntity0=FP-0402-L_1_0_1-W_0_5_0_1-IPC_C|ModelDatafileKind0=PCBLib|IsCurrent=T|DatalinksLocked=T|DatabaseDatalinksLocked=T
|RECORD=46|OwnerIndex=2110
|RECORD=48|OwnerIndex=2110
|RECORD=45|OwnerIndex=2109|IndexInSheet=-1|UseComponentLibrary=T|ModelName=FP-0402-L_1_0_1-W_0_5_0_1-IPC_B|ModelType=PCBLIB|DatafileCount=1|ModelDatafileEntity0=FP-0402-L_1_0_1-W_0_5_0_1-IPC_B|ModelDatafileKind0=PCBLib|DatalinksLocked=T|DatabaseDatalinksLocked=T
|RECORD=46|OwnerIndex=2113
|RECORD=48|OwnerIndex=2113
|RECORD=45|OwnerIndex=2109|IndexInSheet=-1|UseComponentLibrary=T|ModelName=FP-0402-L_1_0_1-W_0_5_0_1-MFG|ModelType=PCBLIB|DatafileCount=1|ModelDatafileEntity0=FP-0402-L_1_0_1-W_0_5_0_1-MFG|ModelDatafileKind0=PCBLib|DatalinksLocked=T|DatabaseDatalinksLocked=T
|RECORD=46|OwnerIndex=2116
|RECORD=48|OwnerIndex=2116
|RECORD=45|OwnerIndex=2109|IndexInSheet=-1|UseComponentLibrary=T|ModelName=FP-0402-L_1_0_1-W_0_5_0_1-IPC_A|ModelType=PCBLIB|DatafileCount=1|ModelDatafileEntity0=FP-0402-L_1_0_1-W_0_5_0_1-IPC_A|ModelDatafileKind0=PCBLib|DatalinksLocked=T|DatabaseDatalinksLocked=T
|RECORD=46|OwnerIndex=2119
|RECORD=48|OwnerIndex=2119
|RECORD=1|LibReference=b4654b650e69147ec39a6b967a45e02|ComponentDescription=General Purpose Ceramic Capacitor, 0402, 100nF, 10%, X7R, 15%, 25V|PartCount=2|DisplayModeCount=1|IndexInSheet=154|OwnerPartId=-1|Location.X=530|Location.Y=170|CurrentPartId=1|LibraryPath=*|SourceLibraryName=Altium Content Vault|TargetFileName=*|AreaColor=11599871|Color=128|PartIDLocked=T|DesignItemId=CMP-2008-02519-2|AllPinCount=2
|RECORD=2|OwnerIndex=2122|OwnerPartId=1|Electrical=4|PinConglomerate=49|PinLength=7|Location.X=530|Location.Y=163|Name=1|Designator=1|PinPropagationDelay=0.000000E+000
|RECORD=2|OwnerIndex=2122|OwnerPartId=1|Electrical=4|PinConglomerate=51|PinLength=6|Location.X=530|Location.Y=156|Name=2|Designator=2|PinPropagationDelay=0.000000E+000
|RECORD=13|OwnerIndex=2122|IsNotAccesible=T|IndexInSheet=2|OwnerPartId=1|Location.X=540|Location.Y=163|Corner.X=520|Corner.Y=163|LineWidth=1|Color=16711680
|RECORD=13|OwnerIndex=2122|IsNotAccesible=T|IndexInSheet=3|OwnerPartId=1|Location.X=540|Location.Y=157|Corner.X=520|Corner.Y=157|LineWidth=1|Color=16711680
|RECORD=13|OwnerIndex=2122|IsNotAccesible=T|IndexInSheet=4|OwnerPartId=1|Location.X=530|Location.Y=163|Corner.X=530|Corner.Y=166|LineWidth=1|Color=16711680
|RECORD=13|OwnerIndex=2122|IsNotAccesible=T|IndexInSheet=5|OwnerPartId=1|Location.X=530|Location.Y=156|Corner.X=530|Corner.Y=155|LineWidth=1|Color=16711680
|RECORD=41|OwnerIndex=2122|IndexInSheet=6|OwnerPartId=-1|Location.X=519|Location.Y=172|Color=8388608|FontID=1|IsHidden=T|Text=1|Name=Package Quantity
|RECORD=41|OwnerIndex=2122|IndexInSheet=7|OwnerPartId=-1|Location.X=519|Location.Y=172|Color=8388608|FontID=1|IsHidden=T|Text=100nF|Name=Capacitance
|RECORD=41|OwnerIndex=2122|IndexInSheet=8|OwnerPartId=-1|Location.X=519|Location.Y=172|Color=8388608|FontID=1|IsHidden=T|Text=-55°C|Name=Min Operating Temperature
|RECORD=41|OwnerIndex=2122|IndexInSheet=9|OwnerPartId=-1|Location.X=519|Location.Y=172|Color=8388608|FontID=1|IsHidden=T|Text=25V|Name=Voltage
|RECORD=41|OwnerIndex=2122|IndexInSheet=10|OwnerPartId=-1|Location.X=519|Location.Y=172|Color=8388608|FontID=1|IsHidden=T|Text=25V|Name=Voltage Rating
|RECORD=41|OwnerIndex=2122|IndexInSheet=11|OwnerPartId=-1|Location.X=519|Location.Y=172|Color=8388608|FontID=1|IsHidden=T|Text=Flat|Name=Construction
|RECORD=41|OwnerIndex=2122|IndexInSheet=12|OwnerPartId=-1|Location.X=519|Location.Y=172|Color=8388608|FontID=1|IsHidden=T|Text=125°C|Name=Max Operating Temperature
|RECORD=41|OwnerIndex=2122|IndexInSheet=13|OwnerPartId=-1|Location.X=519|Location.Y=172|Color=8388608|FontID=1|IsHidden=T|Text=No|Name=Radiation Hardening
|RECORD=41|OwnerIndex=2122|IndexInSheet=14|OwnerPartId=-1|Location.X=519|Location.Y=172|Color=8388608|FontID=1|IsHidden=T|Text=0.5mm|Name=Depth
|RECORD=41|OwnerIndex=2122|IndexInSheet=15|OwnerPartId=-1|Location.X=519|Location.Y=172|Color=8388608|FontID=1|IsHidden=T|Text=0.022inch|Name=Thickness
|RECORD=41|OwnerIndex=2122|IndexInSheet=16|OwnerPartId=-1|Location.X=519|Location.Y=172|Color=8388608|FontID=1|IsHidden=T|Text=25V|Name=Voltage Rating (DC)
|RECORD=41|OwnerIndex=2122|IndexInSheet=17|OwnerPartId=-1|Location.X=519|Location.Y=172|Color=8388608|FontID=1|IsHidden=T|Text=2|Name=Number of Pins
|RECORD=41|OwnerIndex=2122|IndexInSheet=18|OwnerPartId=-1|Location.X=519|Location.Y=172|Color=8388608|FontID=1|IsHidden=T|Text=Lead Free|Name=Lead Free
|RECORD=41|OwnerIndex=2122|IndexInSheet=19|OwnerPartId=-1|Location.X=519|Location.Y=172|Color=8388608|FontID=1|IsHidden=T|Text=-|Name=Series
|RECORD=41|OwnerIndex=2122|IndexInSheet=20|OwnerPartId=-1|Location.X=519|Location.Y=172|Color=8388608|FontID=1|IsHidden=T|Text=No SVHC|Name=REACH SVHC
|RECORD=41|OwnerIndex=2122|IndexInSheet=21|OwnerPartId=-1|Location.X=519|Location.Y=172|Color=8388608|FontID=1|IsHidden=T|Text=1mm|Name=Length
|RECORD=41|OwnerIndex=2122|IndexInSheet=22|OwnerPartId=-1|Location.X=519|Location.Y=172|Color=8388608|FontID=1|IsHidden=T|Text=X7R|Name=Dielectric
|RECORD=41|OwnerIndex=2122|IndexInSheet=23|OwnerPartId=-1|Location.X=519|Location.Y=172|Color=8388608|FontID=1|IsHidden=T|Text=Yes|Name=RoHS Compliant
|RECORD=41|OwnerIndex=2122|IndexInSheet=24|OwnerPartId=-1|Location.X=519|Location.Y=172|Color=8388608|FontID=1|IsHidden=T|Text=Surface Mount|Name=Mount
|RECORD=41|OwnerIndex=2122|IndexInSheet=25|OwnerPartId=-1|Location.X=519|Location.Y=172|Color=8388608|FontID=1|IsHidden=T|Text=Tape and Reel|Name=Packaging
|RECORD=41|OwnerIndex=2122|IndexInSheet=26|OwnerPartId=-1|Location.X=519|Location.Y=172|Color=8388608|FontID=1|IsHidden=T|Text=0402|Name=Case/Package
|RECORD=41|OwnerIndex=2122|IndexInSheet=27|OwnerPartId=-1|Location.X=519|Location.Y=172|Color=8388608|FontID=1|IsHidden=T|Text=0402|Name=Case Code (Imperial)
|RECORD=41|OwnerIndex=2122|IndexInSheet=28|OwnerPartId=-1|Location.X=519|Location.Y=172|Color=8388608|FontID=1|IsHidden=T|Text=SMD/SMT|Name=Termination
|RECORD=41|OwnerIndex=2122|IndexInSheet=29|OwnerPartId=-1|Location.X=519|Location.Y=172|Color=8388608|FontID=1|IsHidden=T|Text=0.02inch|Name=Width
|RECORD=41|OwnerIndex=2122|IndexInSheet=30|OwnerPartId=-1|Location.X=519|Location.Y=172|Color=8388608|FontID=1|IsHidden=T|Text=1005|Name=Case Code (Metric)
|RECORD=41|OwnerIndex=2122|IndexInSheet=31|OwnerPartId=-1|Location.X=519|Location.Y=172|Color=8388608|FontID=1|IsHidden=T|Text=10%|Name=Tolerance
|RECORD=34|OwnerIndex=2122|IndexInSheet=-1|OwnerPartId=-1|Location.X=520|Location.Y=150|Orientation=1|Color=8388608|FontID=2|Text=C97|Name=Designator|ReadOnlyState=1
|RECORD=41|OwnerIndex=2122|IndexInSheet=-1|OwnerPartId=1|Location.X=550|Location.Y=135|Orientation=1|Color=8388608|FontID=2|Text=0.1uF_25V_0402|Name=Comment
|RECORD=44|OwnerIndex=2122
|RECORD=45|OwnerIndex=2159|IndexInSheet=-1|UseComponentLibrary=T|ModelName=FP-0402-L_1_0_1-W_0_5_0_1-IPC_C|ModelType=PCBLIB|DatafileCount=1|ModelDatafileEntity0=FP-0402-L_1_0_1-W_0_5_0_1-IPC_C|ModelDatafileKind0=PCBLib|IsCurrent=T|DatalinksLocked=T|DatabaseDatalinksLocked=T
|RECORD=46|OwnerIndex=2160
|RECORD=48|OwnerIndex=2160
|RECORD=45|OwnerIndex=2159|IndexInSheet=-1|UseComponentLibrary=T|ModelName=FP-0402-L_1_0_1-W_0_5_0_1-IPC_B|ModelType=PCBLIB|DatafileCount=1|ModelDatafileEntity0=FP-0402-L_1_0_1-W_0_5_0_1-IPC_B|ModelDatafileKind0=PCBLib|DatalinksLocked=T|DatabaseDatalinksLocked=T
|RECORD=46|OwnerIndex=2163
|RECORD=48|OwnerIndex=2163
|RECORD=45|OwnerIndex=2159|IndexInSheet=-1|UseComponentLibrary=T|ModelName=FP-0402-L_1_0_1-W_0_5_0_1-MFG|ModelType=PCBLIB|DatafileCount=1|ModelDatafileEntity0=FP-0402-L_1_0_1-W_0_5_0_1-MFG|ModelDatafileKind0=PCBLib|DatalinksLocked=T|DatabaseDatalinksLocked=T
|RECORD=46|OwnerIndex=2166
|RECORD=48|OwnerIndex=2166
|RECORD=45|OwnerIndex=2159|IndexInSheet=-1|UseComponentLibrary=T|ModelName=FP-0402-L_1_0_1-W_0_5_0_1-IPC_A|ModelType=PCBLIB|DatafileCount=1|ModelDatafileEntity0=FP-0402-L_1_0_1-W_0_5_0_1-IPC_A|ModelDatafileKind0=PCBLib|DatalinksLocked=T|DatabaseDatalinksLocked=T
|RECORD=46|OwnerIndex=2169
|RECORD=48|OwnerIndex=2169
|RECORD=1|LibReference=b4654b650e69147ec39a6b967a45e02|ComponentDescription=General Purpose Ceramic Capacitor, 0402, 100nF, 10%, X7R, 15%, 25V|PartCount=2|DisplayModeCount=1|IndexInSheet=155|OwnerPartId=-1|Location.X=570|Location.Y=170|CurrentPartId=1|LibraryPath=*|SourceLibraryName=Altium Content Vault|TargetFileName=*|AreaColor=11599871|Color=128|PartIDLocked=T|DesignItemId=CMP-2008-02519-2|AllPinCount=2
|RECORD=2|OwnerIndex=2172|OwnerPartId=1|Electrical=4|PinConglomerate=49|PinLength=7|Location.X=570|Location.Y=163|Name=1|Designator=1|PinPropagationDelay=0.000000E+000
|RECORD=2|OwnerIndex=2172|OwnerPartId=1|Electrical=4|PinConglomerate=51|PinLength=6|Location.X=570|Location.Y=156|Name=2|Designator=2|PinPropagationDelay=0.000000E+000
|RECORD=13|OwnerIndex=2172|IsNotAccesible=T|IndexInSheet=2|OwnerPartId=1|Location.X=580|Location.Y=163|Corner.X=560|Corner.Y=163|LineWidth=1|Color=16711680
|RECORD=13|OwnerIndex=2172|IsNotAccesible=T|IndexInSheet=3|OwnerPartId=1|Location.X=580|Location.Y=157|Corner.X=560|Corner.Y=157|LineWidth=1|Color=16711680
|RECORD=13|OwnerIndex=2172|IsNotAccesible=T|IndexInSheet=4|OwnerPartId=1|Location.X=570|Location.Y=163|Corner.X=570|Corner.Y=166|LineWidth=1|Color=16711680
|RECORD=13|OwnerIndex=2172|IsNotAccesible=T|IndexInSheet=5|OwnerPartId=1|Location.X=570|Location.Y=156|Corner.X=570|Corner.Y=155|LineWidth=1|Color=16711680
|RECORD=41|OwnerIndex=2172|IndexInSheet=6|OwnerPartId=-1|Location.X=559|Location.Y=172|Color=8388608|FontID=1|IsHidden=T|Text=1|Name=Package Quantity
|RECORD=41|OwnerIndex=2172|IndexInSheet=7|OwnerPartId=-1|Location.X=559|Location.Y=172|Color=8388608|FontID=1|IsHidden=T|Text=100nF|Name=Capacitance
|RECORD=41|OwnerIndex=2172|IndexInSheet=8|OwnerPartId=-1|Location.X=559|Location.Y=172|Color=8388608|FontID=1|IsHidden=T|Text=-55°C|Name=Min Operating Temperature
|RECORD=41|OwnerIndex=2172|IndexInSheet=9|OwnerPartId=-1|Location.X=559|Location.Y=172|Color=8388608|FontID=1|IsHidden=T|Text=25V|Name=Voltage
|RECORD=41|OwnerIndex=2172|IndexInSheet=10|OwnerPartId=-1|Location.X=559|Location.Y=172|Color=8388608|FontID=1|IsHidden=T|Text=25V|Name=Voltage Rating
|RECORD=41|OwnerIndex=2172|IndexInSheet=11|OwnerPartId=-1|Location.X=559|Location.Y=172|Color=8388608|FontID=1|IsHidden=T|Text=Flat|Name=Construction
|RECORD=41|OwnerIndex=2172|IndexInSheet=12|OwnerPartId=-1|Location.X=559|Location.Y=172|Color=8388608|FontID=1|IsHidden=T|Text=125°C|Name=Max Operating Temperature
|RECORD=41|OwnerIndex=2172|IndexInSheet=13|OwnerPartId=-1|Location.X=559|Location.Y=172|Color=8388608|FontID=1|IsHidden=T|Text=No|Name=Radiation Hardening
|RECORD=41|OwnerIndex=2172|IndexInSheet=14|OwnerPartId=-1|Location.X=559|Location.Y=172|Color=8388608|FontID=1|IsHidden=T|Text=0.5mm|Name=Depth
|RECORD=41|OwnerIndex=2172|IndexInSheet=15|OwnerPartId=-1|Location.X=559|Location.Y=172|Color=8388608|FontID=1|IsHidden=T|Text=0.022inch|Name=Thickness
|RECORD=41|OwnerIndex=2172|IndexInSheet=16|OwnerPartId=-1|Location.X=559|Location.Y=172|Color=8388608|FontID=1|IsHidden=T|Text=25V|Name=Voltage Rating (DC)
|RECORD=41|OwnerIndex=2172|IndexInSheet=17|OwnerPartId=-1|Location.X=559|Location.Y=172|Color=8388608|FontID=1|IsHidden=T|Text=2|Name=Number of Pins
|RECORD=41|OwnerIndex=2172|IndexInSheet=18|OwnerPartId=-1|Location.X=559|Location.Y=172|Color=8388608|FontID=1|IsHidden=T|Text=Lead Free|Name=Lead Free
|RECORD=41|OwnerIndex=2172|IndexInSheet=19|OwnerPartId=-1|Location.X=559|Location.Y=172|Color=8388608|FontID=1|IsHidden=T|Text=-|Name=Series
|RECORD=41|OwnerIndex=2172|IndexInSheet=20|OwnerPartId=-1|Location.X=559|Location.Y=172|Color=8388608|FontID=1|IsHidden=T|Text=No SVHC|Name=REACH SVHC
|RECORD=41|OwnerIndex=2172|IndexInSheet=21|OwnerPartId=-1|Location.X=559|Location.Y=172|Color=8388608|FontID=1|IsHidden=T|Text=1mm|Name=Length
|RECORD=41|OwnerIndex=2172|IndexInSheet=22|OwnerPartId=-1|Location.X=559|Location.Y=172|Color=8388608|FontID=1|IsHidden=T|Text=X7R|Name=Dielectric
|RECORD=41|OwnerIndex=2172|IndexInSheet=23|OwnerPartId=-1|Location.X=559|Location.Y=172|Color=8388608|FontID=1|IsHidden=T|Text=Yes|Name=RoHS Compliant
|RECORD=41|OwnerIndex=2172|IndexInSheet=24|OwnerPartId=-1|Location.X=559|Location.Y=172|Color=8388608|FontID=1|IsHidden=T|Text=Surface Mount|Name=Mount
|RECORD=41|OwnerIndex=2172|IndexInSheet=25|OwnerPartId=-1|Location.X=559|Location.Y=172|Color=8388608|FontID=1|IsHidden=T|Text=Tape and Reel|Name=Packaging
|RECORD=41|OwnerIndex=2172|IndexInSheet=26|OwnerPartId=-1|Location.X=559|Location.Y=172|Color=8388608|FontID=1|IsHidden=T|Text=0402|Name=Case/Package
|RECORD=41|OwnerIndex=2172|IndexInSheet=27|OwnerPartId=-1|Location.X=559|Location.Y=172|Color=8388608|FontID=1|IsHidden=T|Text=0402|Name=Case Code (Imperial)
|RECORD=41|OwnerIndex=2172|IndexInSheet=28|OwnerPartId=-1|Location.X=559|Location.Y=172|Color=8388608|FontID=1|IsHidden=T|Text=SMD/SMT|Name=Termination
|RECORD=41|OwnerIndex=2172|IndexInSheet=29|OwnerPartId=-1|Location.X=559|Location.Y=172|Color=8388608|FontID=1|IsHidden=T|Text=0.02inch|Name=Width
|RECORD=41|OwnerIndex=2172|IndexInSheet=30|OwnerPartId=-1|Location.X=559|Location.Y=172|Color=8388608|FontID=1|IsHidden=T|Text=1005|Name=Case Code (Metric)
|RECORD=41|OwnerIndex=2172|IndexInSheet=31|OwnerPartId=-1|Location.X=559|Location.Y=172|Color=8388608|FontID=1|IsHidden=T|Text=10%|Name=Tolerance
|RECORD=34|OwnerIndex=2172|IndexInSheet=-1|OwnerPartId=-1|Location.X=560|Location.Y=150|Orientation=1|Color=8388608|FontID=2|Text=C98|Name=Designator|ReadOnlyState=1
|RECORD=41|OwnerIndex=2172|IndexInSheet=-1|OwnerPartId=1|Location.X=590|Location.Y=135|Orientation=1|Color=8388608|FontID=2|Text=0.1uF_25V_0402|Name=Comment
|RECORD=44|OwnerIndex=2172
|RECORD=45|OwnerIndex=2209|IndexInSheet=-1|UseComponentLibrary=T|ModelName=FP-0402-L_1_0_1-W_0_5_0_1-IPC_C|ModelType=PCBLIB|DatafileCount=1|ModelDatafileEntity0=FP-0402-L_1_0_1-W_0_5_0_1-IPC_C|ModelDatafileKind0=PCBLib|IsCurrent=T|DatalinksLocked=T|DatabaseDatalinksLocked=T
|RECORD=46|OwnerIndex=2210
|RECORD=48|OwnerIndex=2210
|RECORD=45|OwnerIndex=2209|IndexInSheet=-1|UseComponentLibrary=T|ModelName=FP-0402-L_1_0_1-W_0_5_0_1-IPC_B|ModelType=PCBLIB|DatafileCount=1|ModelDatafileEntity0=FP-0402-L_1_0_1-W_0_5_0_1-IPC_B|ModelDatafileKind0=PCBLib|DatalinksLocked=T|DatabaseDatalinksLocked=T
|RECORD=46|OwnerIndex=2213
|RECORD=48|OwnerIndex=2213
|RECORD=45|OwnerIndex=2209|IndexInSheet=-1|UseComponentLibrary=T|ModelName=FP-0402-L_1_0_1-W_0_5_0_1-MFG|ModelType=PCBLIB|DatafileCount=1|ModelDatafileEntity0=FP-0402-L_1_0_1-W_0_5_0_1-MFG|ModelDatafileKind0=PCBLib|DatalinksLocked=T|DatabaseDatalinksLocked=T
|RECORD=46|OwnerIndex=2216
|RECORD=48|OwnerIndex=2216
|RECORD=45|OwnerIndex=2209|IndexInSheet=-1|UseComponentLibrary=T|ModelName=FP-0402-L_1_0_1-W_0_5_0_1-IPC_A|ModelType=PCBLIB|DatafileCount=1|ModelDatafileEntity0=FP-0402-L_1_0_1-W_0_5_0_1-IPC_A|ModelDatafileKind0=PCBLib|DatalinksLocked=T|DatabaseDatalinksLocked=T
|RECORD=46|OwnerIndex=2219
|RECORD=48|OwnerIndex=2219
|RECORD=1|LibReference=b4654b650e69147ec39a6b967a45e02|ComponentDescription=General Purpose Ceramic Capacitor, 0402, 100nF, 10%, X7R, 15%, 25V|PartCount=2|DisplayModeCount=1|IndexInSheet=156|OwnerPartId=-1|Location.X=610|Location.Y=170|CurrentPartId=1|LibraryPath=*|SourceLibraryName=Altium Content Vault|TargetFileName=*|AreaColor=11599871|Color=128|PartIDLocked=T|DesignItemId=CMP-2008-02519-2|AllPinCount=2
|RECORD=2|OwnerIndex=2222|OwnerPartId=1|Electrical=4|PinConglomerate=49|PinLength=7|Location.X=610|Location.Y=163|Name=1|Designator=1|PinPropagationDelay=0.000000E+000
|RECORD=2|OwnerIndex=2222|OwnerPartId=1|Electrical=4|PinConglomerate=51|PinLength=6|Location.X=610|Location.Y=156|Name=2|Designator=2|PinPropagationDelay=0.000000E+000
|RECORD=13|OwnerIndex=2222|IsNotAccesible=T|IndexInSheet=2|OwnerPartId=1|Location.X=620|Location.Y=163|Corner.X=600|Corner.Y=163|LineWidth=1|Color=16711680
|RECORD=13|OwnerIndex=2222|IsNotAccesible=T|IndexInSheet=3|OwnerPartId=1|Location.X=620|Location.Y=157|Corner.X=600|Corner.Y=157|LineWidth=1|Color=16711680
|RECORD=13|OwnerIndex=2222|IsNotAccesible=T|IndexInSheet=4|OwnerPartId=1|Location.X=610|Location.Y=163|Corner.X=610|Corner.Y=166|LineWidth=1|Color=16711680
|RECORD=13|OwnerIndex=2222|IsNotAccesible=T|IndexInSheet=5|OwnerPartId=1|Location.X=610|Location.Y=156|Corner.X=610|Corner.Y=155|LineWidth=1|Color=16711680
|RECORD=41|OwnerIndex=2222|IndexInSheet=6|OwnerPartId=-1|Location.X=599|Location.Y=172|Color=8388608|FontID=1|IsHidden=T|Text=1|Name=Package Quantity
|RECORD=41|OwnerIndex=2222|IndexInSheet=7|OwnerPartId=-1|Location.X=599|Location.Y=172|Color=8388608|FontID=1|IsHidden=T|Text=100nF|Name=Capacitance
|RECORD=41|OwnerIndex=2222|IndexInSheet=8|OwnerPartId=-1|Location.X=599|Location.Y=172|Color=8388608|FontID=1|IsHidden=T|Text=-55°C|Name=Min Operating Temperature
|RECORD=41|OwnerIndex=2222|IndexInSheet=9|OwnerPartId=-1|Location.X=599|Location.Y=172|Color=8388608|FontID=1|IsHidden=T|Text=25V|Name=Voltage
|RECORD=41|OwnerIndex=2222|IndexInSheet=10|OwnerPartId=-1|Location.X=599|Location.Y=172|Color=8388608|FontID=1|IsHidden=T|Text=25V|Name=Voltage Rating
|RECORD=41|OwnerIndex=2222|IndexInSheet=11|OwnerPartId=-1|Location.X=599|Location.Y=172|Color=8388608|FontID=1|IsHidden=T|Text=Flat|Name=Construction
|RECORD=41|OwnerIndex=2222|IndexInSheet=12|OwnerPartId=-1|Location.X=599|Location.Y=172|Color=8388608|FontID=1|IsHidden=T|Text=125°C|Name=Max Operating Temperature
|RECORD=41|OwnerIndex=2222|IndexInSheet=13|OwnerPartId=-1|Location.X=599|Location.Y=172|Color=8388608|FontID=1|IsHidden=T|Text=No|Name=Radiation Hardening
|RECORD=41|OwnerIndex=2222|IndexInSheet=14|OwnerPartId=-1|Location.X=599|Location.Y=172|Color=8388608|FontID=1|IsHidden=T|Text=0.5mm|Name=Depth
|RECORD=41|OwnerIndex=2222|IndexInSheet=15|OwnerPartId=-1|Location.X=599|Location.Y=172|Color=8388608|FontID=1|IsHidden=T|Text=0.022inch|Name=Thickness
|RECORD=41|OwnerIndex=2222|IndexInSheet=16|OwnerPartId=-1|Location.X=599|Location.Y=172|Color=8388608|FontID=1|IsHidden=T|Text=25V|Name=Voltage Rating (DC)
|RECORD=41|OwnerIndex=2222|IndexInSheet=17|OwnerPartId=-1|Location.X=599|Location.Y=172|Color=8388608|FontID=1|IsHidden=T|Text=2|Name=Number of Pins
|RECORD=41|OwnerIndex=2222|IndexInSheet=18|OwnerPartId=-1|Location.X=599|Location.Y=172|Color=8388608|FontID=1|IsHidden=T|Text=Lead Free|Name=Lead Free
|RECORD=41|OwnerIndex=2222|IndexInSheet=19|OwnerPartId=-1|Location.X=599|Location.Y=172|Color=8388608|FontID=1|IsHidden=T|Text=-|Name=Series
|RECORD=41|OwnerIndex=2222|IndexInSheet=20|OwnerPartId=-1|Location.X=599|Location.Y=172|Color=8388608|FontID=1|IsHidden=T|Text=No SVHC|Name=REACH SVHC
|RECORD=41|OwnerIndex=2222|IndexInSheet=21|OwnerPartId=-1|Location.X=599|Location.Y=172|Color=8388608|FontID=1|IsHidden=T|Text=1mm|Name=Length
|RECORD=41|OwnerIndex=2222|IndexInSheet=22|OwnerPartId=-1|Location.X=599|Location.Y=172|Color=8388608|FontID=1|IsHidden=T|Text=X7R|Name=Dielectric
|RECORD=41|OwnerIndex=2222|IndexInSheet=23|OwnerPartId=-1|Location.X=599|Location.Y=172|Color=8388608|FontID=1|IsHidden=T|Text=Yes|Name=RoHS Compliant
|RECORD=41|OwnerIndex=2222|IndexInSheet=24|OwnerPartId=-1|Location.X=599|Location.Y=172|Color=8388608|FontID=1|IsHidden=T|Text=Surface Mount|Name=Mount
|RECORD=41|OwnerIndex=2222|IndexInSheet=25|OwnerPartId=-1|Location.X=599|Location.Y=172|Color=8388608|FontID=1|IsHidden=T|Text=Tape and Reel|Name=Packaging
|RECORD=41|OwnerIndex=2222|IndexInSheet=26|OwnerPartId=-1|Location.X=599|Location.Y=172|Color=8388608|FontID=1|IsHidden=T|Text=0402|Name=Case/Package
|RECORD=41|OwnerIndex=2222|IndexInSheet=27|OwnerPartId=-1|Location.X=599|Location.Y=172|Color=8388608|FontID=1|IsHidden=T|Text=0402|Name=Case Code (Imperial)
|RECORD=41|OwnerIndex=2222|IndexInSheet=28|OwnerPartId=-1|Location.X=599|Location.Y=172|Color=8388608|FontID=1|IsHidden=T|Text=SMD/SMT|Name=Termination
|RECORD=41|OwnerIndex=2222|IndexInSheet=29|OwnerPartId=-1|Location.X=599|Location.Y=172|Color=8388608|FontID=1|IsHidden=T|Text=0.02inch|Name=Width
|RECORD=41|OwnerIndex=2222|IndexInSheet=30|OwnerPartId=-1|Location.X=599|Location.Y=172|Color=8388608|FontID=1|IsHidden=T|Text=1005|Name=Case Code (Metric)
|RECORD=41|OwnerIndex=2222|IndexInSheet=31|OwnerPartId=-1|Location.X=599|Location.Y=172|Color=8388608|FontID=1|IsHidden=T|Text=10%|Name=Tolerance
|RECORD=34|OwnerIndex=2222|IndexInSheet=-1|OwnerPartId=-1|Location.X=600|Location.Y=150|Orientation=1|Color=8388608|FontID=2|Text=C99|Name=Designator|ReadOnlyState=1
|RECORD=41|OwnerIndex=2222|IndexInSheet=-1|OwnerPartId=1|Location.X=630|Location.Y=135|Orientation=1|Color=8388608|FontID=2|Text=0.1uF_25V_0402|Name=Comment
|RECORD=44|OwnerIndex=2222
|RECORD=45|OwnerIndex=2259|IndexInSheet=-1|UseComponentLibrary=T|ModelName=FP-0402-L_1_0_1-W_0_5_0_1-IPC_C|ModelType=PCBLIB|DatafileCount=1|ModelDatafileEntity0=FP-0402-L_1_0_1-W_0_5_0_1-IPC_C|ModelDatafileKind0=PCBLib|IsCurrent=T|DatalinksLocked=T|DatabaseDatalinksLocked=T
|RECORD=46|OwnerIndex=2260
|RECORD=48|OwnerIndex=2260
|RECORD=45|OwnerIndex=2259|IndexInSheet=-1|UseComponentLibrary=T|ModelName=FP-0402-L_1_0_1-W_0_5_0_1-IPC_B|ModelType=PCBLIB|DatafileCount=1|ModelDatafileEntity0=FP-0402-L_1_0_1-W_0_5_0_1-IPC_B|ModelDatafileKind0=PCBLib|DatalinksLocked=T|DatabaseDatalinksLocked=T
|RECORD=46|OwnerIndex=2263
|RECORD=48|OwnerIndex=2263
|RECORD=45|OwnerIndex=2259|IndexInSheet=-1|UseComponentLibrary=T|ModelName=FP-0402-L_1_0_1-W_0_5_0_1-MFG|ModelType=PCBLIB|DatafileCount=1|ModelDatafileEntity0=FP-0402-L_1_0_1-W_0_5_0_1-MFG|ModelDatafileKind0=PCBLib|DatalinksLocked=T|DatabaseDatalinksLocked=T
|RECORD=46|OwnerIndex=2266
|RECORD=48|OwnerIndex=2266
|RECORD=45|OwnerIndex=2259|IndexInSheet=-1|UseComponentLibrary=T|ModelName=FP-0402-L_1_0_1-W_0_5_0_1-IPC_A|ModelType=PCBLIB|DatafileCount=1|ModelDatafileEntity0=FP-0402-L_1_0_1-W_0_5_0_1-IPC_A|ModelDatafileKind0=PCBLib|DatalinksLocked=T|DatabaseDatalinksLocked=T
|RECORD=46|OwnerIndex=2269
|RECORD=48|OwnerIndex=2269
|RECORD=1|LibReference=b4654b650e69147ec39a6b967a45e02|ComponentDescription=General Purpose Ceramic Capacitor, 0402, 100nF, 10%, X7R, 15%, 25V|PartCount=2|DisplayModeCount=1|IndexInSheet=157|OwnerPartId=-1|Location.X=650|Location.Y=170|CurrentPartId=1|LibraryPath=*|SourceLibraryName=Altium Content Vault|TargetFileName=*|AreaColor=11599871|Color=128|PartIDLocked=T|DesignItemId=CMP-2008-02519-2|AllPinCount=2
|RECORD=2|OwnerIndex=2272|OwnerPartId=1|Electrical=4|PinConglomerate=49|PinLength=7|Location.X=650|Location.Y=163|Name=1|Designator=1|PinPropagationDelay=0.000000E+000
|RECORD=2|OwnerIndex=2272|OwnerPartId=1|Electrical=4|PinConglomerate=51|PinLength=6|Location.X=650|Location.Y=156|Name=2|Designator=2|PinPropagationDelay=0.000000E+000
|RECORD=13|OwnerIndex=2272|IsNotAccesible=T|IndexInSheet=2|OwnerPartId=1|Location.X=660|Location.Y=163|Corner.X=640|Corner.Y=163|LineWidth=1|Color=16711680
|RECORD=13|OwnerIndex=2272|IsNotAccesible=T|IndexInSheet=3|OwnerPartId=1|Location.X=660|Location.Y=157|Corner.X=640|Corner.Y=157|LineWidth=1|Color=16711680
|RECORD=13|OwnerIndex=2272|IsNotAccesible=T|IndexInSheet=4|OwnerPartId=1|Location.X=650|Location.Y=163|Corner.X=650|Corner.Y=166|LineWidth=1|Color=16711680
|RECORD=13|OwnerIndex=2272|IsNotAccesible=T|IndexInSheet=5|OwnerPartId=1|Location.X=650|Location.Y=156|Corner.X=650|Corner.Y=155|LineWidth=1|Color=16711680
|RECORD=41|OwnerIndex=2272|IndexInSheet=6|OwnerPartId=-1|Location.X=639|Location.Y=172|Color=8388608|FontID=1|IsHidden=T|Text=1|Name=Package Quantity
|RECORD=41|OwnerIndex=2272|IndexInSheet=7|OwnerPartId=-1|Location.X=639|Location.Y=172|Color=8388608|FontID=1|IsHidden=T|Text=100nF|Name=Capacitance
|RECORD=41|OwnerIndex=2272|IndexInSheet=8|OwnerPartId=-1|Location.X=639|Location.Y=172|Color=8388608|FontID=1|IsHidden=T|Text=-55°C|Name=Min Operating Temperature
|RECORD=41|OwnerIndex=2272|IndexInSheet=9|OwnerPartId=-1|Location.X=639|Location.Y=172|Color=8388608|FontID=1|IsHidden=T|Text=25V|Name=Voltage
|RECORD=41|OwnerIndex=2272|IndexInSheet=10|OwnerPartId=-1|Location.X=639|Location.Y=172|Color=8388608|FontID=1|IsHidden=T|Text=25V|Name=Voltage Rating
|RECORD=41|OwnerIndex=2272|IndexInSheet=11|OwnerPartId=-1|Location.X=639|Location.Y=172|Color=8388608|FontID=1|IsHidden=T|Text=Flat|Name=Construction
|RECORD=41|OwnerIndex=2272|IndexInSheet=12|OwnerPartId=-1|Location.X=639|Location.Y=172|Color=8388608|FontID=1|IsHidden=T|Text=125°C|Name=Max Operating Temperature
|RECORD=41|OwnerIndex=2272|IndexInSheet=13|OwnerPartId=-1|Location.X=639|Location.Y=172|Color=8388608|FontID=1|IsHidden=T|Text=No|Name=Radiation Hardening
|RECORD=41|OwnerIndex=2272|IndexInSheet=14|OwnerPartId=-1|Location.X=639|Location.Y=172|Color=8388608|FontID=1|IsHidden=T|Text=0.5mm|Name=Depth
|RECORD=41|OwnerIndex=2272|IndexInSheet=15|OwnerPartId=-1|Location.X=639|Location.Y=172|Color=8388608|FontID=1|IsHidden=T|Text=0.022inch|Name=Thickness
|RECORD=41|OwnerIndex=2272|IndexInSheet=16|OwnerPartId=-1|Location.X=639|Location.Y=172|Color=8388608|FontID=1|IsHidden=T|Text=25V|Name=Voltage Rating (DC)
|RECORD=41|OwnerIndex=2272|IndexInSheet=17|OwnerPartId=-1|Location.X=639|Location.Y=172|Color=8388608|FontID=1|IsHidden=T|Text=2|Name=Number of Pins
|RECORD=41|OwnerIndex=2272|IndexInSheet=18|OwnerPartId=-1|Location.X=639|Location.Y=172|Color=8388608|FontID=1|IsHidden=T|Text=Lead Free|Name=Lead Free
|RECORD=41|OwnerIndex=2272|IndexInSheet=19|OwnerPartId=-1|Location.X=639|Location.Y=172|Color=8388608|FontID=1|IsHidden=T|Text=-|Name=Series
|RECORD=41|OwnerIndex=2272|IndexInSheet=20|OwnerPartId=-1|Location.X=639|Location.Y=172|Color=8388608|FontID=1|IsHidden=T|Text=No SVHC|Name=REACH SVHC
|RECORD=41|OwnerIndex=2272|IndexInSheet=21|OwnerPartId=-1|Location.X=639|Location.Y=172|Color=8388608|FontID=1|IsHidden=T|Text=1mm|Name=Length
|RECORD=41|OwnerIndex=2272|IndexInSheet=22|OwnerPartId=-1|Location.X=639|Location.Y=172|Color=8388608|FontID=1|IsHidden=T|Text=X7R|Name=Dielectric
|RECORD=41|OwnerIndex=2272|IndexInSheet=23|OwnerPartId=-1|Location.X=639|Location.Y=172|Color=8388608|FontID=1|IsHidden=T|Text=Yes|Name=RoHS Compliant
|RECORD=41|OwnerIndex=2272|IndexInSheet=24|OwnerPartId=-1|Location.X=639|Location.Y=172|Color=8388608|FontID=1|IsHidden=T|Text=Surface Mount|Name=Mount
|RECORD=41|OwnerIndex=2272|IndexInSheet=25|OwnerPartId=-1|Location.X=639|Location.Y=172|Color=8388608|FontID=1|IsHidden=T|Text=Tape and Reel|Name=Packaging
|RECORD=41|OwnerIndex=2272|IndexInSheet=26|OwnerPartId=-1|Location.X=639|Location.Y=172|Color=8388608|FontID=1|IsHidden=T|Text=0402|Name=Case/Package
|RECORD=41|OwnerIndex=2272|IndexInSheet=27|OwnerPartId=-1|Location.X=639|Location.Y=172|Color=8388608|FontID=1|IsHidden=T|Text=0402|Name=Case Code (Imperial)
|RECORD=41|OwnerIndex=2272|IndexInSheet=28|OwnerPartId=-1|Location.X=639|Location.Y=172|Color=8388608|FontID=1|IsHidden=T|Text=SMD/SMT|Name=Termination
|RECORD=41|OwnerIndex=2272|IndexInSheet=29|OwnerPartId=-1|Location.X=639|Location.Y=172|Color=8388608|FontID=1|IsHidden=T|Text=0.02inch|Name=Width
|RECORD=41|OwnerIndex=2272|IndexInSheet=30|OwnerPartId=-1|Location.X=639|Location.Y=172|Color=8388608|FontID=1|IsHidden=T|Text=1005|Name=Case Code (Metric)
|RECORD=41|OwnerIndex=2272|IndexInSheet=31|OwnerPartId=-1|Location.X=639|Location.Y=172|Color=8388608|FontID=1|IsHidden=T|Text=10%|Name=Tolerance
|RECORD=34|OwnerIndex=2272|IndexInSheet=-1|OwnerPartId=-1|Location.X=640|Location.Y=150|Orientation=1|Color=8388608|FontID=2|Text=C100|Name=Designator|ReadOnlyState=1
|RECORD=41|OwnerIndex=2272|IndexInSheet=-1|OwnerPartId=1|Location.X=670|Location.Y=135|Orientation=1|Color=8388608|FontID=2|Text=0.1uF_25V_0402|Name=Comment
|RECORD=44|OwnerIndex=2272
|RECORD=45|OwnerIndex=2309|IndexInSheet=-1|UseComponentLibrary=T|ModelName=FP-0402-L_1_0_1-W_0_5_0_1-IPC_C|ModelType=PCBLIB|DatafileCount=1|ModelDatafileEntity0=FP-0402-L_1_0_1-W_0_5_0_1-IPC_C|ModelDatafileKind0=PCBLib|IsCurrent=T|DatalinksLocked=T|DatabaseDatalinksLocked=T
|RECORD=46|OwnerIndex=2310
|RECORD=48|OwnerIndex=2310
|RECORD=45|OwnerIndex=2309|IndexInSheet=-1|UseComponentLibrary=T|ModelName=FP-0402-L_1_0_1-W_0_5_0_1-IPC_B|ModelType=PCBLIB|DatafileCount=1|ModelDatafileEntity0=FP-0402-L_1_0_1-W_0_5_0_1-IPC_B|ModelDatafileKind0=PCBLib|DatalinksLocked=T|DatabaseDatalinksLocked=T
|RECORD=46|OwnerIndex=2313
|RECORD=48|OwnerIndex=2313
|RECORD=45|OwnerIndex=2309|IndexInSheet=-1|UseComponentLibrary=T|ModelName=FP-0402-L_1_0_1-W_0_5_0_1-MFG|ModelType=PCBLIB|DatafileCount=1|ModelDatafileEntity0=FP-0402-L_1_0_1-W_0_5_0_1-MFG|ModelDatafileKind0=PCBLib|DatalinksLocked=T|DatabaseDatalinksLocked=T
|RECORD=46|OwnerIndex=2316
|RECORD=48|OwnerIndex=2316
|RECORD=45|OwnerIndex=2309|IndexInSheet=-1|UseComponentLibrary=T|ModelName=FP-0402-L_1_0_1-W_0_5_0_1-IPC_A|ModelType=PCBLIB|DatafileCount=1|ModelDatafileEntity0=FP-0402-L_1_0_1-W_0_5_0_1-IPC_A|ModelDatafileKind0=PCBLib|DatalinksLocked=T|DatabaseDatalinksLocked=T
|RECORD=46|OwnerIndex=2319
|RECORD=48|OwnerIndex=2319
|RECORD=27|IndexInSheet=158|OwnerPartId=-1|LineWidth=1|Color=8388608|LocationCount=3|X1=460|Y1=200|X2=490|Y2=200|X3=490|Y3=170
|RECORD=27|IndexInSheet=159|OwnerPartId=-1|LineWidth=1|Color=8388608|LocationCount=3|X1=490|Y1=200|X2=530|Y2=200|X3=530|Y3=170
|RECORD=27|IndexInSheet=160|OwnerPartId=-1|LineWidth=1|Color=8388608|LocationCount=3|X1=530|Y1=200|X2=570|Y2=200|X3=570|Y3=170
|RECORD=27|IndexInSheet=161|OwnerPartId=-1|LineWidth=1|Color=8388608|LocationCount=3|X1=570|Y1=200|X2=610|Y2=200|X3=610|Y3=170
|RECORD=27|IndexInSheet=162|OwnerPartId=-1|LineWidth=1|Color=8388608|LocationCount=3|X1=610|Y1=200|X2=650|Y2=200|X3=650|Y3=170
|RECORD=27|IndexInSheet=163|OwnerPartId=-1|LineWidth=1|Color=8388608|LocationCount=3|X1=490|Y1=150|X2=490|Y2=130|X3=460|Y3=130
|RECORD=27|IndexInSheet=164|OwnerPartId=-1|LineWidth=1|Color=8388608|LocationCount=3|X1=530|Y1=150|X2=530|Y2=130|X3=490|Y3=130
|RECORD=27|IndexInSheet=165|OwnerPartId=-1|LineWidth=1|Color=8388608|LocationCount=5|X1=650|Y1=150|X2=650|Y2=130|X3=610|Y3=130|X4=570|Y4=130|X5=530|Y5=130
|RECORD=27|IndexInSheet=166|OwnerPartId=-1|LineWidth=1|Color=8388608|LocationCount=2|X1=570|Y1=150|X2=570|Y2=130
|RECORD=27|IndexInSheet=167|OwnerPartId=-1|LineWidth=1|Color=8388608|LocationCount=2|X1=610|Y1=150|X2=610|Y2=130
|RECORD=1|LibReference=b4654b650e69147ec39a6b967a45e02|ComponentDescription=General Purpose Ceramic Capacitor, 0402, 100nF, 10%, X7R, 15%, 25V|PartCount=2|DisplayModeCount=1|IndexInSheet=168|OwnerPartId=-1|Location.X=1120|Location.Y=170|CurrentPartId=1|LibraryPath=*|SourceLibraryName=Altium Content Vault|TargetFileName=*|AreaColor=11599871|Color=128|PartIDLocked=T|DesignItemId=CMP-2008-02519-2|AllPinCount=2
|RECORD=2|OwnerIndex=2332|OwnerPartId=1|Electrical=4|PinConglomerate=49|PinLength=7|Location.X=1120|Location.Y=163|Name=1|Designator=1|PinPropagationDelay=0.000000E+000
|RECORD=2|OwnerIndex=2332|OwnerPartId=1|Electrical=4|PinConglomerate=51|PinLength=6|Location.X=1120|Location.Y=156|Name=2|Designator=2|PinPropagationDelay=0.000000E+000
|RECORD=13|OwnerIndex=2332|IsNotAccesible=T|IndexInSheet=2|OwnerPartId=1|Location.X=1130|Location.Y=163|Corner.X=1110|Corner.Y=163|LineWidth=1|Color=16711680
|RECORD=13|OwnerIndex=2332|IsNotAccesible=T|IndexInSheet=3|OwnerPartId=1|Location.X=1130|Location.Y=157|Corner.X=1110|Corner.Y=157|LineWidth=1|Color=16711680
|RECORD=13|OwnerIndex=2332|IsNotAccesible=T|IndexInSheet=4|OwnerPartId=1|Location.X=1120|Location.Y=163|Corner.X=1120|Corner.Y=166|LineWidth=1|Color=16711680
|RECORD=13|OwnerIndex=2332|IsNotAccesible=T|IndexInSheet=5|OwnerPartId=1|Location.X=1120|Location.Y=156|Corner.X=1120|Corner.Y=155|LineWidth=1|Color=16711680
|RECORD=41|OwnerIndex=2332|IndexInSheet=6|OwnerPartId=-1|Location.X=1109|Location.Y=172|Color=8388608|FontID=1|IsHidden=T|Text=1|Name=Package Quantity
|RECORD=41|OwnerIndex=2332|IndexInSheet=7|OwnerPartId=-1|Location.X=1109|Location.Y=172|Color=8388608|FontID=1|IsHidden=T|Text=100nF|Name=Capacitance
|RECORD=41|OwnerIndex=2332|IndexInSheet=8|OwnerPartId=-1|Location.X=1109|Location.Y=172|Color=8388608|FontID=1|IsHidden=T|Text=-55°C|Name=Min Operating Temperature
|RECORD=41|OwnerIndex=2332|IndexInSheet=9|OwnerPartId=-1|Location.X=1109|Location.Y=172|Color=8388608|FontID=1|IsHidden=T|Text=25V|Name=Voltage
|RECORD=41|OwnerIndex=2332|IndexInSheet=10|OwnerPartId=-1|Location.X=1109|Location.Y=172|Color=8388608|FontID=1|IsHidden=T|Text=25V|Name=Voltage Rating
|RECORD=41|OwnerIndex=2332|IndexInSheet=11|OwnerPartId=-1|Location.X=1109|Location.Y=172|Color=8388608|FontID=1|IsHidden=T|Text=Flat|Name=Construction
|RECORD=41|OwnerIndex=2332|IndexInSheet=12|OwnerPartId=-1|Location.X=1109|Location.Y=172|Color=8388608|FontID=1|IsHidden=T|Text=125°C|Name=Max Operating Temperature
|RECORD=41|OwnerIndex=2332|IndexInSheet=13|OwnerPartId=-1|Location.X=1109|Location.Y=172|Color=8388608|FontID=1|IsHidden=T|Text=No|Name=Radiation Hardening
|RECORD=41|OwnerIndex=2332|IndexInSheet=14|OwnerPartId=-1|Location.X=1109|Location.Y=172|Color=8388608|FontID=1|IsHidden=T|Text=0.5mm|Name=Depth
|RECORD=41|OwnerIndex=2332|IndexInSheet=15|OwnerPartId=-1|Location.X=1109|Location.Y=172|Color=8388608|FontID=1|IsHidden=T|Text=0.022inch|Name=Thickness
|RECORD=41|OwnerIndex=2332|IndexInSheet=16|OwnerPartId=-1|Location.X=1109|Location.Y=172|Color=8388608|FontID=1|IsHidden=T|Text=25V|Name=Voltage Rating (DC)
|RECORD=41|OwnerIndex=2332|IndexInSheet=17|OwnerPartId=-1|Location.X=1109|Location.Y=172|Color=8388608|FontID=1|IsHidden=T|Text=2|Name=Number of Pins
|RECORD=41|OwnerIndex=2332|IndexInSheet=18|OwnerPartId=-1|Location.X=1109|Location.Y=172|Color=8388608|FontID=1|IsHidden=T|Text=Lead Free|Name=Lead Free
|RECORD=41|OwnerIndex=2332|IndexInSheet=19|OwnerPartId=-1|Location.X=1109|Location.Y=172|Color=8388608|FontID=1|IsHidden=T|Text=-|Name=Series
|RECORD=41|OwnerIndex=2332|IndexInSheet=20|OwnerPartId=-1|Location.X=1109|Location.Y=172|Color=8388608|FontID=1|IsHidden=T|Text=No SVHC|Name=REACH SVHC
|RECORD=41|OwnerIndex=2332|IndexInSheet=21|OwnerPartId=-1|Location.X=1109|Location.Y=172|Color=8388608|FontID=1|IsHidden=T|Text=1mm|Name=Length
|RECORD=41|OwnerIndex=2332|IndexInSheet=22|OwnerPartId=-1|Location.X=1109|Location.Y=172|Color=8388608|FontID=1|IsHidden=T|Text=X7R|Name=Dielectric
|RECORD=41|OwnerIndex=2332|IndexInSheet=23|OwnerPartId=-1|Location.X=1109|Location.Y=172|Color=8388608|FontID=1|IsHidden=T|Text=Yes|Name=RoHS Compliant
|RECORD=41|OwnerIndex=2332|IndexInSheet=24|OwnerPartId=-1|Location.X=1109|Location.Y=172|Color=8388608|FontID=1|IsHidden=T|Text=Surface Mount|Name=Mount
|RECORD=41|OwnerIndex=2332|IndexInSheet=25|OwnerPartId=-1|Location.X=1109|Location.Y=172|Color=8388608|FontID=1|IsHidden=T|Text=Tape and Reel|Name=Packaging
|RECORD=41|OwnerIndex=2332|IndexInSheet=26|OwnerPartId=-1|Location.X=1109|Location.Y=172|Color=8388608|FontID=1|IsHidden=T|Text=0402|Name=Case/Package
|RECORD=41|OwnerIndex=2332|IndexInSheet=27|OwnerPartId=-1|Location.X=1109|Location.Y=172|Color=8388608|FontID=1|IsHidden=T|Text=0402|Name=Case Code (Imperial)
|RECORD=41|OwnerIndex=2332|IndexInSheet=28|OwnerPartId=-1|Location.X=1109|Location.Y=172|Color=8388608|FontID=1|IsHidden=T|Text=SMD/SMT|Name=Termination
|RECORD=41|OwnerIndex=2332|IndexInSheet=29|OwnerPartId=-1|Location.X=1109|Location.Y=172|Color=8388608|FontID=1|IsHidden=T|Text=0.02inch|Name=Width
|RECORD=41|OwnerIndex=2332|IndexInSheet=30|OwnerPartId=-1|Location.X=1109|Location.Y=172|Color=8388608|FontID=1|IsHidden=T|Text=1005|Name=Case Code (Metric)
|RECORD=41|OwnerIndex=2332|IndexInSheet=31|OwnerPartId=-1|Location.X=1109|Location.Y=172|Color=8388608|FontID=1|IsHidden=T|Text=10%|Name=Tolerance
|RECORD=34|OwnerIndex=2332|IndexInSheet=-1|OwnerPartId=-1|Location.X=1110|Location.Y=150|Orientation=1|Color=8388608|FontID=2|Text=C101|Name=Designator|ReadOnlyState=1
|RECORD=41|OwnerIndex=2332|IndexInSheet=-1|OwnerPartId=1|Location.X=1140|Location.Y=135|Orientation=1|Color=8388608|FontID=2|Text=0.1uF_25V_0402|Name=Comment
|RECORD=44|OwnerIndex=2332
|RECORD=45|OwnerIndex=2369|IndexInSheet=-1|UseComponentLibrary=T|ModelName=FP-0402-L_1_0_1-W_0_5_0_1-IPC_C|ModelType=PCBLIB|DatafileCount=1|ModelDatafileEntity0=FP-0402-L_1_0_1-W_0_5_0_1-IPC_C|ModelDatafileKind0=PCBLib|IsCurrent=T|DatalinksLocked=T|DatabaseDatalinksLocked=T
|RECORD=46|OwnerIndex=2370
|RECORD=48|OwnerIndex=2370
|RECORD=45|OwnerIndex=2369|IndexInSheet=-1|UseComponentLibrary=T|ModelName=FP-0402-L_1_0_1-W_0_5_0_1-IPC_B|ModelType=PCBLIB|DatafileCount=1|ModelDatafileEntity0=FP-0402-L_1_0_1-W_0_5_0_1-IPC_B|ModelDatafileKind0=PCBLib|DatalinksLocked=T|DatabaseDatalinksLocked=T
|RECORD=46|OwnerIndex=2373
|RECORD=48|OwnerIndex=2373
|RECORD=45|OwnerIndex=2369|IndexInSheet=-1|UseComponentLibrary=T|ModelName=FP-0402-L_1_0_1-W_0_5_0_1-MFG|ModelType=PCBLIB|DatafileCount=1|ModelDatafileEntity0=FP-0402-L_1_0_1-W_0_5_0_1-MFG|ModelDatafileKind0=PCBLib|DatalinksLocked=T|DatabaseDatalinksLocked=T
|RECORD=46|OwnerIndex=2376
|RECORD=48|OwnerIndex=2376
|RECORD=45|OwnerIndex=2369|IndexInSheet=-1|UseComponentLibrary=T|ModelName=FP-0402-L_1_0_1-W_0_5_0_1-IPC_A|ModelType=PCBLIB|DatafileCount=1|ModelDatafileEntity0=FP-0402-L_1_0_1-W_0_5_0_1-IPC_A|ModelDatafileKind0=PCBLib|DatalinksLocked=T|DatabaseDatalinksLocked=T
|RECORD=46|OwnerIndex=2379
|RECORD=48|OwnerIndex=2379
|RECORD=1|LibReference=b4654b650e69147ec39a6b967a45e02|ComponentDescription=General Purpose Ceramic Capacitor, 0402, 100nF, 10%, X7R, 15%, 25V|PartCount=2|DisplayModeCount=1|IndexInSheet=169|OwnerPartId=-1|Location.X=1160|Location.Y=170|CurrentPartId=1|LibraryPath=*|SourceLibraryName=Altium Content Vault|TargetFileName=*|AreaColor=11599871|Color=128|PartIDLocked=T|DesignItemId=CMP-2008-02519-2|AllPinCount=2
|RECORD=2|OwnerIndex=2382|OwnerPartId=1|Electrical=4|PinConglomerate=49|PinLength=7|Location.X=1160|Location.Y=163|Name=1|Designator=1|PinPropagationDelay=0.000000E+000
|RECORD=2|OwnerIndex=2382|OwnerPartId=1|Electrical=4|PinConglomerate=51|PinLength=6|Location.X=1160|Location.Y=156|Name=2|Designator=2|PinPropagationDelay=0.000000E+000
|RECORD=13|OwnerIndex=2382|IsNotAccesible=T|IndexInSheet=2|OwnerPartId=1|Location.X=1170|Location.Y=163|Corner.X=1150|Corner.Y=163|LineWidth=1|Color=16711680
|RECORD=13|OwnerIndex=2382|IsNotAccesible=T|IndexInSheet=3|OwnerPartId=1|Location.X=1170|Location.Y=157|Corner.X=1150|Corner.Y=157|LineWidth=1|Color=16711680
|RECORD=13|OwnerIndex=2382|IsNotAccesible=T|IndexInSheet=4|OwnerPartId=1|Location.X=1160|Location.Y=163|Corner.X=1160|Corner.Y=166|LineWidth=1|Color=16711680
|RECORD=13|OwnerIndex=2382|IsNotAccesible=T|IndexInSheet=5|OwnerPartId=1|Location.X=1160|Location.Y=156|Corner.X=1160|Corner.Y=155|LineWidth=1|Color=16711680
|RECORD=41|OwnerIndex=2382|IndexInSheet=6|OwnerPartId=-1|Location.X=1149|Location.Y=172|Color=8388608|FontID=1|IsHidden=T|Text=1|Name=Package Quantity
|RECORD=41|OwnerIndex=2382|IndexInSheet=7|OwnerPartId=-1|Location.X=1149|Location.Y=172|Color=8388608|FontID=1|IsHidden=T|Text=100nF|Name=Capacitance
|RECORD=41|OwnerIndex=2382|IndexInSheet=8|OwnerPartId=-1|Location.X=1149|Location.Y=172|Color=8388608|FontID=1|IsHidden=T|Text=-55°C|Name=Min Operating Temperature
|RECORD=41|OwnerIndex=2382|IndexInSheet=9|OwnerPartId=-1|Location.X=1149|Location.Y=172|Color=8388608|FontID=1|IsHidden=T|Text=25V|Name=Voltage
|RECORD=41|OwnerIndex=2382|IndexInSheet=10|OwnerPartId=-1|Location.X=1149|Location.Y=172|Color=8388608|FontID=1|IsHidden=T|Text=25V|Name=Voltage Rating
|RECORD=41|OwnerIndex=2382|IndexInSheet=11|OwnerPartId=-1|Location.X=1149|Location.Y=172|Color=8388608|FontID=1|IsHidden=T|Text=Flat|Name=Construction
|RECORD=41|OwnerIndex=2382|IndexInSheet=12|OwnerPartId=-1|Location.X=1149|Location.Y=172|Color=8388608|FontID=1|IsHidden=T|Text=125°C|Name=Max Operating Temperature
|RECORD=41|OwnerIndex=2382|IndexInSheet=13|OwnerPartId=-1|Location.X=1149|Location.Y=172|Color=8388608|FontID=1|IsHidden=T|Text=No|Name=Radiation Hardening
|RECORD=41|OwnerIndex=2382|IndexInSheet=14|OwnerPartId=-1|Location.X=1149|Location.Y=172|Color=8388608|FontID=1|IsHidden=T|Text=0.5mm|Name=Depth
|RECORD=41|OwnerIndex=2382|IndexInSheet=15|OwnerPartId=-1|Location.X=1149|Location.Y=172|Color=8388608|FontID=1|IsHidden=T|Text=0.022inch|Name=Thickness
|RECORD=41|OwnerIndex=2382|IndexInSheet=16|OwnerPartId=-1|Location.X=1149|Location.Y=172|Color=8388608|FontID=1|IsHidden=T|Text=25V|Name=Voltage Rating (DC)
|RECORD=41|OwnerIndex=2382|IndexInSheet=17|OwnerPartId=-1|Location.X=1149|Location.Y=172|Color=8388608|FontID=1|IsHidden=T|Text=2|Name=Number of Pins
|RECORD=41|OwnerIndex=2382|IndexInSheet=18|OwnerPartId=-1|Location.X=1149|Location.Y=172|Color=8388608|FontID=1|IsHidden=T|Text=Lead Free|Name=Lead Free
|RECORD=41|OwnerIndex=2382|IndexInSheet=19|OwnerPartId=-1|Location.X=1149|Location.Y=172|Color=8388608|FontID=1|IsHidden=T|Text=-|Name=Series
|RECORD=41|OwnerIndex=2382|IndexInSheet=20|OwnerPartId=-1|Location.X=1149|Location.Y=172|Color=8388608|FontID=1|IsHidden=T|Text=No SVHC|Name=REACH SVHC
|RECORD=41|OwnerIndex=2382|IndexInSheet=21|OwnerPartId=-1|Location.X=1149|Location.Y=172|Color=8388608|FontID=1|IsHidden=T|Text=1mm|Name=Length
|RECORD=41|OwnerIndex=2382|IndexInSheet=22|OwnerPartId=-1|Location.X=1149|Location.Y=172|Color=8388608|FontID=1|IsHidden=T|Text=X7R|Name=Dielectric
|RECORD=41|OwnerIndex=2382|IndexInSheet=23|OwnerPartId=-1|Location.X=1149|Location.Y=172|Color=8388608|FontID=1|IsHidden=T|Text=Yes|Name=RoHS Compliant
|RECORD=41|OwnerIndex=2382|IndexInSheet=24|OwnerPartId=-1|Location.X=1149|Location.Y=172|Color=8388608|FontID=1|IsHidden=T|Text=Surface Mount|Name=Mount
|RECORD=41|OwnerIndex=2382|IndexInSheet=25|OwnerPartId=-1|Location.X=1149|Location.Y=172|Color=8388608|FontID=1|IsHidden=T|Text=Tape and Reel|Name=Packaging
|RECORD=41|OwnerIndex=2382|IndexInSheet=26|OwnerPartId=-1|Location.X=1149|Location.Y=172|Color=8388608|FontID=1|IsHidden=T|Text=0402|Name=Case/Package
|RECORD=41|OwnerIndex=2382|IndexInSheet=27|OwnerPartId=-1|Location.X=1149|Location.Y=172|Color=8388608|FontID=1|IsHidden=T|Text=0402|Name=Case Code (Imperial)
|RECORD=41|OwnerIndex=2382|IndexInSheet=28|OwnerPartId=-1|Location.X=1149|Location.Y=172|Color=8388608|FontID=1|IsHidden=T|Text=SMD/SMT|Name=Termination
|RECORD=41|OwnerIndex=2382|IndexInSheet=29|OwnerPartId=-1|Location.X=1149|Location.Y=172|Color=8388608|FontID=1|IsHidden=T|Text=0.02inch|Name=Width
|RECORD=41|OwnerIndex=2382|IndexInSheet=30|OwnerPartId=-1|Location.X=1149|Location.Y=172|Color=8388608|FontID=1|IsHidden=T|Text=1005|Name=Case Code (Metric)
|RECORD=41|OwnerIndex=2382|IndexInSheet=31|OwnerPartId=-1|Location.X=1149|Location.Y=172|Color=8388608|FontID=1|IsHidden=T|Text=10%|Name=Tolerance
|RECORD=34|OwnerIndex=2382|IndexInSheet=-1|OwnerPartId=-1|Location.X=1150|Location.Y=150|Orientation=1|Color=8388608|FontID=2|Text=C102|Name=Designator|ReadOnlyState=1
|RECORD=41|OwnerIndex=2382|IndexInSheet=-1|OwnerPartId=1|Location.X=1180|Location.Y=135|Orientation=1|Color=8388608|FontID=2|Text=0.1uF_25V_0402|Name=Comment
|RECORD=44|OwnerIndex=2382
|RECORD=45|OwnerIndex=2419|IndexInSheet=-1|UseComponentLibrary=T|ModelName=FP-0402-L_1_0_1-W_0_5_0_1-IPC_C|ModelType=PCBLIB|DatafileCount=1|ModelDatafileEntity0=FP-0402-L_1_0_1-W_0_5_0_1-IPC_C|ModelDatafileKind0=PCBLib|IsCurrent=T|DatalinksLocked=T|DatabaseDatalinksLocked=T
|RECORD=46|OwnerIndex=2420
|RECORD=48|OwnerIndex=2420
|RECORD=45|OwnerIndex=2419|IndexInSheet=-1|UseComponentLibrary=T|ModelName=FP-0402-L_1_0_1-W_0_5_0_1-IPC_B|ModelType=PCBLIB|DatafileCount=1|ModelDatafileEntity0=FP-0402-L_1_0_1-W_0_5_0_1-IPC_B|ModelDatafileKind0=PCBLib|DatalinksLocked=T|DatabaseDatalinksLocked=T
|RECORD=46|OwnerIndex=2423
|RECORD=48|OwnerIndex=2423
|RECORD=45|OwnerIndex=2419|IndexInSheet=-1|UseComponentLibrary=T|ModelName=FP-0402-L_1_0_1-W_0_5_0_1-MFG|ModelType=PCBLIB|DatafileCount=1|ModelDatafileEntity0=FP-0402-L_1_0_1-W_0_5_0_1-MFG|ModelDatafileKind0=PCBLib|DatalinksLocked=T|DatabaseDatalinksLocked=T
|RECORD=46|OwnerIndex=2426
|RECORD=48|OwnerIndex=2426
|RECORD=45|OwnerIndex=2419|IndexInSheet=-1|UseComponentLibrary=T|ModelName=FP-0402-L_1_0_1-W_0_5_0_1-IPC_A|ModelType=PCBLIB|DatafileCount=1|ModelDatafileEntity0=FP-0402-L_1_0_1-W_0_5_0_1-IPC_A|ModelDatafileKind0=PCBLib|DatalinksLocked=T|DatabaseDatalinksLocked=T
|RECORD=46|OwnerIndex=2429
|RECORD=48|OwnerIndex=2429
|RECORD=1|LibReference=b4654b650e69147ec39a6b967a45e02|ComponentDescription=General Purpose Ceramic Capacitor, 0402, 100nF, 10%, X7R, 15%, 25V|PartCount=2|DisplayModeCount=1|IndexInSheet=170|OwnerPartId=-1|Location.X=1200|Location.Y=170|CurrentPartId=1|LibraryPath=*|SourceLibraryName=Altium Content Vault|TargetFileName=*|AreaColor=11599871|Color=128|PartIDLocked=T|DesignItemId=CMP-2008-02519-2|AllPinCount=2
|RECORD=2|OwnerIndex=2432|OwnerPartId=1|Electrical=4|PinConglomerate=49|PinLength=7|Location.X=1200|Location.Y=163|Name=1|Designator=1|PinPropagationDelay=0.000000E+000
|RECORD=2|OwnerIndex=2432|OwnerPartId=1|Electrical=4|PinConglomerate=51|PinLength=6|Location.X=1200|Location.Y=156|Name=2|Designator=2|PinPropagationDelay=0.000000E+000
|RECORD=13|OwnerIndex=2432|IsNotAccesible=T|IndexInSheet=2|OwnerPartId=1|Location.X=1210|Location.Y=163|Corner.X=1190|Corner.Y=163|LineWidth=1|Color=16711680
|RECORD=13|OwnerIndex=2432|IsNotAccesible=T|IndexInSheet=3|OwnerPartId=1|Location.X=1210|Location.Y=157|Corner.X=1190|Corner.Y=157|LineWidth=1|Color=16711680
|RECORD=13|OwnerIndex=2432|IsNotAccesible=T|IndexInSheet=4|OwnerPartId=1|Location.X=1200|Location.Y=163|Corner.X=1200|Corner.Y=166|LineWidth=1|Color=16711680
|RECORD=13|OwnerIndex=2432|IsNotAccesible=T|IndexInSheet=5|OwnerPartId=1|Location.X=1200|Location.Y=156|Corner.X=1200|Corner.Y=155|LineWidth=1|Color=16711680
|RECORD=41|OwnerIndex=2432|IndexInSheet=6|OwnerPartId=-1|Location.X=1189|Location.Y=172|Color=8388608|FontID=1|IsHidden=T|Text=1|Name=Package Quantity
|RECORD=41|OwnerIndex=2432|IndexInSheet=7|OwnerPartId=-1|Location.X=1189|Location.Y=172|Color=8388608|FontID=1|IsHidden=T|Text=100nF|Name=Capacitance
|RECORD=41|OwnerIndex=2432|IndexInSheet=8|OwnerPartId=-1|Location.X=1189|Location.Y=172|Color=8388608|FontID=1|IsHidden=T|Text=-55°C|Name=Min Operating Temperature
|RECORD=41|OwnerIndex=2432|IndexInSheet=9|OwnerPartId=-1|Location.X=1189|Location.Y=172|Color=8388608|FontID=1|IsHidden=T|Text=25V|Name=Voltage
|RECORD=41|OwnerIndex=2432|IndexInSheet=10|OwnerPartId=-1|Location.X=1189|Location.Y=172|Color=8388608|FontID=1|IsHidden=T|Text=25V|Name=Voltage Rating
|RECORD=41|OwnerIndex=2432|IndexInSheet=11|OwnerPartId=-1|Location.X=1189|Location.Y=172|Color=8388608|FontID=1|IsHidden=T|Text=Flat|Name=Construction
|RECORD=41|OwnerIndex=2432|IndexInSheet=12|OwnerPartId=-1|Location.X=1189|Location.Y=172|Color=8388608|FontID=1|IsHidden=T|Text=125°C|Name=Max Operating Temperature
|RECORD=41|OwnerIndex=2432|IndexInSheet=13|OwnerPartId=-1|Location.X=1189|Location.Y=172|Color=8388608|FontID=1|IsHidden=T|Text=No|Name=Radiation Hardening
|RECORD=41|OwnerIndex=2432|IndexInSheet=14|OwnerPartId=-1|Location.X=1189|Location.Y=172|Color=8388608|FontID=1|IsHidden=T|Text=0.5mm|Name=Depth
|RECORD=41|OwnerIndex=2432|IndexInSheet=15|OwnerPartId=-1|Location.X=1189|Location.Y=172|Color=8388608|FontID=1|IsHidden=T|Text=0.022inch|Name=Thickness
|RECORD=41|OwnerIndex=2432|IndexInSheet=16|OwnerPartId=-1|Location.X=1189|Location.Y=172|Color=8388608|FontID=1|IsHidden=T|Text=25V|Name=Voltage Rating (DC)
|RECORD=41|OwnerIndex=2432|IndexInSheet=17|OwnerPartId=-1|Location.X=1189|Location.Y=172|Color=8388608|FontID=1|IsHidden=T|Text=2|Name=Number of Pins
|RECORD=41|OwnerIndex=2432|IndexInSheet=18|OwnerPartId=-1|Location.X=1189|Location.Y=172|Color=8388608|FontID=1|IsHidden=T|Text=Lead Free|Name=Lead Free
|RECORD=41|OwnerIndex=2432|IndexInSheet=19|OwnerPartId=-1|Location.X=1189|Location.Y=172|Color=8388608|FontID=1|IsHidden=T|Text=-|Name=Series
|RECORD=41|OwnerIndex=2432|IndexInSheet=20|OwnerPartId=-1|Location.X=1189|Location.Y=172|Color=8388608|FontID=1|IsHidden=T|Text=No SVHC|Name=REACH SVHC
|RECORD=41|OwnerIndex=2432|IndexInSheet=21|OwnerPartId=-1|Location.X=1189|Location.Y=172|Color=8388608|FontID=1|IsHidden=T|Text=1mm|Name=Length
|RECORD=41|OwnerIndex=2432|IndexInSheet=22|OwnerPartId=-1|Location.X=1189|Location.Y=172|Color=8388608|FontID=1|IsHidden=T|Text=X7R|Name=Dielectric
|RECORD=41|OwnerIndex=2432|IndexInSheet=23|OwnerPartId=-1|Location.X=1189|Location.Y=172|Color=8388608|FontID=1|IsHidden=T|Text=Yes|Name=RoHS Compliant
|RECORD=41|OwnerIndex=2432|IndexInSheet=24|OwnerPartId=-1|Location.X=1189|Location.Y=172|Color=8388608|FontID=1|IsHidden=T|Text=Surface Mount|Name=Mount
|RECORD=41|OwnerIndex=2432|IndexInSheet=25|OwnerPartId=-1|Location.X=1189|Location.Y=172|Color=8388608|FontID=1|IsHidden=T|Text=Tape and Reel|Name=Packaging
|RECORD=41|OwnerIndex=2432|IndexInSheet=26|OwnerPartId=-1|Location.X=1189|Location.Y=172|Color=8388608|FontID=1|IsHidden=T|Text=0402|Name=Case/Package
|RECORD=41|OwnerIndex=2432|IndexInSheet=27|OwnerPartId=-1|Location.X=1189|Location.Y=172|Color=8388608|FontID=1|IsHidden=T|Text=0402|Name=Case Code (Imperial)
|RECORD=41|OwnerIndex=2432|IndexInSheet=28|OwnerPartId=-1|Location.X=1189|Location.Y=172|Color=8388608|FontID=1|IsHidden=T|Text=SMD/SMT|Name=Termination
|RECORD=41|OwnerIndex=2432|IndexInSheet=29|OwnerPartId=-1|Location.X=1189|Location.Y=172|Color=8388608|FontID=1|IsHidden=T|Text=0.02inch|Name=Width
|RECORD=41|OwnerIndex=2432|IndexInSheet=30|OwnerPartId=-1|Location.X=1189|Location.Y=172|Color=8388608|FontID=1|IsHidden=T|Text=1005|Name=Case Code (Metric)
|RECORD=41|OwnerIndex=2432|IndexInSheet=31|OwnerPartId=-1|Location.X=1189|Location.Y=172|Color=8388608|FontID=1|IsHidden=T|Text=10%|Name=Tolerance
|RECORD=34|OwnerIndex=2432|IndexInSheet=-1|OwnerPartId=-1|Location.X=1190|Location.Y=150|Orientation=1|Color=8388608|FontID=2|Text=C103|Name=Designator|ReadOnlyState=1
|RECORD=41|OwnerIndex=2432|IndexInSheet=-1|OwnerPartId=1|Location.X=1220|Location.Y=135|Orientation=1|Color=8388608|FontID=2|Text=0.1uF_25V_0402|Name=Comment
|RECORD=44|OwnerIndex=2432
|RECORD=45|OwnerIndex=2469|IndexInSheet=-1|UseComponentLibrary=T|ModelName=FP-0402-L_1_0_1-W_0_5_0_1-IPC_C|ModelType=PCBLIB|DatafileCount=1|ModelDatafileEntity0=FP-0402-L_1_0_1-W_0_5_0_1-IPC_C|ModelDatafileKind0=PCBLib|IsCurrent=T|DatalinksLocked=T|DatabaseDatalinksLocked=T
|RECORD=46|OwnerIndex=2470
|RECORD=48|OwnerIndex=2470
|RECORD=45|OwnerIndex=2469|IndexInSheet=-1|UseComponentLibrary=T|ModelName=FP-0402-L_1_0_1-W_0_5_0_1-IPC_B|ModelType=PCBLIB|DatafileCount=1|ModelDatafileEntity0=FP-0402-L_1_0_1-W_0_5_0_1-IPC_B|ModelDatafileKind0=PCBLib|DatalinksLocked=T|DatabaseDatalinksLocked=T
|RECORD=46|OwnerIndex=2473
|RECORD=48|OwnerIndex=2473
|RECORD=45|OwnerIndex=2469|IndexInSheet=-1|UseComponentLibrary=T|ModelName=FP-0402-L_1_0_1-W_0_5_0_1-MFG|ModelType=PCBLIB|DatafileCount=1|ModelDatafileEntity0=FP-0402-L_1_0_1-W_0_5_0_1-MFG|ModelDatafileKind0=PCBLib|DatalinksLocked=T|DatabaseDatalinksLocked=T
|RECORD=46|OwnerIndex=2476
|RECORD=48|OwnerIndex=2476
|RECORD=45|OwnerIndex=2469|IndexInSheet=-1|UseComponentLibrary=T|ModelName=FP-0402-L_1_0_1-W_0_5_0_1-IPC_A|ModelType=PCBLIB|DatafileCount=1|ModelDatafileEntity0=FP-0402-L_1_0_1-W_0_5_0_1-IPC_A|ModelDatafileKind0=PCBLib|DatalinksLocked=T|DatabaseDatalinksLocked=T
|RECORD=46|OwnerIndex=2479
|RECORD=48|OwnerIndex=2479
|RECORD=1|LibReference=b4654b650e69147ec39a6b967a45e02|ComponentDescription=General Purpose Ceramic Capacitor, 0402, 100nF, 10%, X7R, 15%, 25V|PartCount=2|DisplayModeCount=1|IndexInSheet=171|OwnerPartId=-1|Location.X=1240|Location.Y=170|CurrentPartId=1|LibraryPath=*|SourceLibraryName=Altium Content Vault|TargetFileName=*|AreaColor=11599871|Color=128|PartIDLocked=T|DesignItemId=CMP-2008-02519-2|AllPinCount=2
|RECORD=2|OwnerIndex=2482|OwnerPartId=1|Electrical=4|PinConglomerate=49|PinLength=7|Location.X=1240|Location.Y=163|Name=1|Designator=1|PinPropagationDelay=0.000000E+000
|RECORD=2|OwnerIndex=2482|OwnerPartId=1|Electrical=4|PinConglomerate=51|PinLength=6|Location.X=1240|Location.Y=156|Name=2|Designator=2|PinPropagationDelay=0.000000E+000
|RECORD=13|OwnerIndex=2482|IsNotAccesible=T|IndexInSheet=2|OwnerPartId=1|Location.X=1250|Location.Y=163|Corner.X=1230|Corner.Y=163|LineWidth=1|Color=16711680
|RECORD=13|OwnerIndex=2482|IsNotAccesible=T|IndexInSheet=3|OwnerPartId=1|Location.X=1250|Location.Y=157|Corner.X=1230|Corner.Y=157|LineWidth=1|Color=16711680
|RECORD=13|OwnerIndex=2482|IsNotAccesible=T|IndexInSheet=4|OwnerPartId=1|Location.X=1240|Location.Y=163|Corner.X=1240|Corner.Y=166|LineWidth=1|Color=16711680
|RECORD=13|OwnerIndex=2482|IsNotAccesible=T|IndexInSheet=5|OwnerPartId=1|Location.X=1240|Location.Y=156|Corner.X=1240|Corner.Y=155|LineWidth=1|Color=16711680
|RECORD=41|OwnerIndex=2482|IndexInSheet=6|OwnerPartId=-1|Location.X=1229|Location.Y=172|Color=8388608|FontID=1|IsHidden=T|Text=1|Name=Package Quantity
|RECORD=41|OwnerIndex=2482|IndexInSheet=7|OwnerPartId=-1|Location.X=1229|Location.Y=172|Color=8388608|FontID=1|IsHidden=T|Text=100nF|Name=Capacitance
|RECORD=41|OwnerIndex=2482|IndexInSheet=8|OwnerPartId=-1|Location.X=1229|Location.Y=172|Color=8388608|FontID=1|IsHidden=T|Text=-55°C|Name=Min Operating Temperature
|RECORD=41|OwnerIndex=2482|IndexInSheet=9|OwnerPartId=-1|Location.X=1229|Location.Y=172|Color=8388608|FontID=1|IsHidden=T|Text=25V|Name=Voltage
|RECORD=41|OwnerIndex=2482|IndexInSheet=10|OwnerPartId=-1|Location.X=1229|Location.Y=172|Color=8388608|FontID=1|IsHidden=T|Text=25V|Name=Voltage Rating
|RECORD=41|OwnerIndex=2482|IndexInSheet=11|OwnerPartId=-1|Location.X=1229|Location.Y=172|Color=8388608|FontID=1|IsHidden=T|Text=Flat|Name=Construction
|RECORD=41|OwnerIndex=2482|IndexInSheet=12|OwnerPartId=-1|Location.X=1229|Location.Y=172|Color=8388608|FontID=1|IsHidden=T|Text=125°C|Name=Max Operating Temperature
|RECORD=41|OwnerIndex=2482|IndexInSheet=13|OwnerPartId=-1|Location.X=1229|Location.Y=172|Color=8388608|FontID=1|IsHidden=T|Text=No|Name=Radiation Hardening
|RECORD=41|OwnerIndex=2482|IndexInSheet=14|OwnerPartId=-1|Location.X=1229|Location.Y=172|Color=8388608|FontID=1|IsHidden=T|Text=0.5mm|Name=Depth
|RECORD=41|OwnerIndex=2482|IndexInSheet=15|OwnerPartId=-1|Location.X=1229|Location.Y=172|Color=8388608|FontID=1|IsHidden=T|Text=0.022inch|Name=Thickness
|RECORD=41|OwnerIndex=2482|IndexInSheet=16|OwnerPartId=-1|Location.X=1229|Location.Y=172|Color=8388608|FontID=1|IsHidden=T|Text=25V|Name=Voltage Rating (DC)
|RECORD=41|OwnerIndex=2482|IndexInSheet=17|OwnerPartId=-1|Location.X=1229|Location.Y=172|Color=8388608|FontID=1|IsHidden=T|Text=2|Name=Number of Pins
|RECORD=41|OwnerIndex=2482|IndexInSheet=18|OwnerPartId=-1|Location.X=1229|Location.Y=172|Color=8388608|FontID=1|IsHidden=T|Text=Lead Free|Name=Lead Free
|RECORD=41|OwnerIndex=2482|IndexInSheet=19|OwnerPartId=-1|Location.X=1229|Location.Y=172|Color=8388608|FontID=1|IsHidden=T|Text=-|Name=Series
|RECORD=41|OwnerIndex=2482|IndexInSheet=20|OwnerPartId=-1|Location.X=1229|Location.Y=172|Color=8388608|FontID=1|IsHidden=T|Text=No SVHC|Name=REACH SVHC
|RECORD=41|OwnerIndex=2482|IndexInSheet=21|OwnerPartId=-1|Location.X=1229|Location.Y=172|Color=8388608|FontID=1|IsHidden=T|Text=1mm|Name=Length
|RECORD=41|OwnerIndex=2482|IndexInSheet=22|OwnerPartId=-1|Location.X=1229|Location.Y=172|Color=8388608|FontID=1|IsHidden=T|Text=X7R|Name=Dielectric
|RECORD=41|OwnerIndex=2482|IndexInSheet=23|OwnerPartId=-1|Location.X=1229|Location.Y=172|Color=8388608|FontID=1|IsHidden=T|Text=Yes|Name=RoHS Compliant
|RECORD=41|OwnerIndex=2482|IndexInSheet=24|OwnerPartId=-1|Location.X=1229|Location.Y=172|Color=8388608|FontID=1|IsHidden=T|Text=Surface Mount|Name=Mount
|RECORD=41|OwnerIndex=2482|IndexInSheet=25|OwnerPartId=-1|Location.X=1229|Location.Y=172|Color=8388608|FontID=1|IsHidden=T|Text=Tape and Reel|Name=Packaging
|RECORD=41|OwnerIndex=2482|IndexInSheet=26|OwnerPartId=-1|Location.X=1229|Location.Y=172|Color=8388608|FontID=1|IsHidden=T|Text=0402|Name=Case/Package
|RECORD=41|OwnerIndex=2482|IndexInSheet=27|OwnerPartId=-1|Location.X=1229|Location.Y=172|Color=8388608|FontID=1|IsHidden=T|Text=0402|Name=Case Code (Imperial)
|RECORD=41|OwnerIndex=2482|IndexInSheet=28|OwnerPartId=-1|Location.X=1229|Location.Y=172|Color=8388608|FontID=1|IsHidden=T|Text=SMD/SMT|Name=Termination
|RECORD=41|OwnerIndex=2482|IndexInSheet=29|OwnerPartId=-1|Location.X=1229|Location.Y=172|Color=8388608|FontID=1|IsHidden=T|Text=0.02inch|Name=Width
|RECORD=41|OwnerIndex=2482|IndexInSheet=30|OwnerPartId=-1|Location.X=1229|Location.Y=172|Color=8388608|FontID=1|IsHidden=T|Text=1005|Name=Case Code (Metric)
|RECORD=41|OwnerIndex=2482|IndexInSheet=31|OwnerPartId=-1|Location.X=1229|Location.Y=172|Color=8388608|FontID=1|IsHidden=T|Text=10%|Name=Tolerance
|RECORD=34|OwnerIndex=2482|IndexInSheet=-1|OwnerPartId=-1|Location.X=1230|Location.Y=150|Orientation=1|Color=8388608|FontID=2|Text=C104|Name=Designator|ReadOnlyState=1
|RECORD=41|OwnerIndex=2482|IndexInSheet=-1|OwnerPartId=1|Location.X=1260|Location.Y=135|Orientation=1|Color=8388608|FontID=2|Text=0.1uF_25V_0402|Name=Comment
|RECORD=44|OwnerIndex=2482
|RECORD=45|OwnerIndex=2519|IndexInSheet=-1|UseComponentLibrary=T|ModelName=FP-0402-L_1_0_1-W_0_5_0_1-IPC_C|ModelType=PCBLIB|DatafileCount=1|ModelDatafileEntity0=FP-0402-L_1_0_1-W_0_5_0_1-IPC_C|ModelDatafileKind0=PCBLib|IsCurrent=T|DatalinksLocked=T|DatabaseDatalinksLocked=T
|RECORD=46|OwnerIndex=2520
|RECORD=48|OwnerIndex=2520
|RECORD=45|OwnerIndex=2519|IndexInSheet=-1|UseComponentLibrary=T|ModelName=FP-0402-L_1_0_1-W_0_5_0_1-IPC_B|ModelType=PCBLIB|DatafileCount=1|ModelDatafileEntity0=FP-0402-L_1_0_1-W_0_5_0_1-IPC_B|ModelDatafileKind0=PCBLib|DatalinksLocked=T|DatabaseDatalinksLocked=T
|RECORD=46|OwnerIndex=2523
|RECORD=48|OwnerIndex=2523
|RECORD=45|OwnerIndex=2519|IndexInSheet=-1|UseComponentLibrary=T|ModelName=FP-0402-L_1_0_1-W_0_5_0_1-MFG|ModelType=PCBLIB|DatafileCount=1|ModelDatafileEntity0=FP-0402-L_1_0_1-W_0_5_0_1-MFG|ModelDatafileKind0=PCBLib|DatalinksLocked=T|DatabaseDatalinksLocked=T
|RECORD=46|OwnerIndex=2526
|RECORD=48|OwnerIndex=2526
|RECORD=45|OwnerIndex=2519|IndexInSheet=-1|UseComponentLibrary=T|ModelName=FP-0402-L_1_0_1-W_0_5_0_1-IPC_A|ModelType=PCBLIB|DatafileCount=1|ModelDatafileEntity0=FP-0402-L_1_0_1-W_0_5_0_1-IPC_A|ModelDatafileKind0=PCBLib|DatalinksLocked=T|DatabaseDatalinksLocked=T
|RECORD=46|OwnerIndex=2529
|RECORD=48|OwnerIndex=2529
|RECORD=1|LibReference=b4654b650e69147ec39a6b967a45e02|ComponentDescription=General Purpose Ceramic Capacitor, 0402, 100nF, 10%, X7R, 15%, 25V|PartCount=2|DisplayModeCount=1|IndexInSheet=172|OwnerPartId=-1|Location.X=1280|Location.Y=170|CurrentPartId=1|LibraryPath=*|SourceLibraryName=Altium Content Vault|TargetFileName=*|AreaColor=11599871|Color=128|PartIDLocked=T|DesignItemId=CMP-2008-02519-2|AllPinCount=2
|RECORD=2|OwnerIndex=2532|OwnerPartId=1|Electrical=4|PinConglomerate=49|PinLength=7|Location.X=1280|Location.Y=163|Name=1|Designator=1|PinPropagationDelay=0.000000E+000
|RECORD=2|OwnerIndex=2532|OwnerPartId=1|Electrical=4|PinConglomerate=51|PinLength=6|Location.X=1280|Location.Y=156|Name=2|Designator=2|PinPropagationDelay=0.000000E+000
|RECORD=13|OwnerIndex=2532|IsNotAccesible=T|IndexInSheet=2|OwnerPartId=1|Location.X=1290|Location.Y=163|Corner.X=1270|Corner.Y=163|LineWidth=1|Color=16711680
|RECORD=13|OwnerIndex=2532|IsNotAccesible=T|IndexInSheet=3|OwnerPartId=1|Location.X=1290|Location.Y=157|Corner.X=1270|Corner.Y=157|LineWidth=1|Color=16711680
|RECORD=13|OwnerIndex=2532|IsNotAccesible=T|IndexInSheet=4|OwnerPartId=1|Location.X=1280|Location.Y=163|Corner.X=1280|Corner.Y=166|LineWidth=1|Color=16711680
|RECORD=13|OwnerIndex=2532|IsNotAccesible=T|IndexInSheet=5|OwnerPartId=1|Location.X=1280|Location.Y=156|Corner.X=1280|Corner.Y=155|LineWidth=1|Color=16711680
|RECORD=41|OwnerIndex=2532|IndexInSheet=6|OwnerPartId=-1|Location.X=1269|Location.Y=172|Color=8388608|FontID=1|IsHidden=T|Text=1|Name=Package Quantity
|RECORD=41|OwnerIndex=2532|IndexInSheet=7|OwnerPartId=-1|Location.X=1269|Location.Y=172|Color=8388608|FontID=1|IsHidden=T|Text=100nF|Name=Capacitance
|RECORD=41|OwnerIndex=2532|IndexInSheet=8|OwnerPartId=-1|Location.X=1269|Location.Y=172|Color=8388608|FontID=1|IsHidden=T|Text=-55°C|Name=Min Operating Temperature
|RECORD=41|OwnerIndex=2532|IndexInSheet=9|OwnerPartId=-1|Location.X=1269|Location.Y=172|Color=8388608|FontID=1|IsHidden=T|Text=25V|Name=Voltage
|RECORD=41|OwnerIndex=2532|IndexInSheet=10|OwnerPartId=-1|Location.X=1269|Location.Y=172|Color=8388608|FontID=1|IsHidden=T|Text=25V|Name=Voltage Rating
|RECORD=41|OwnerIndex=2532|IndexInSheet=11|OwnerPartId=-1|Location.X=1269|Location.Y=172|Color=8388608|FontID=1|IsHidden=T|Text=Flat|Name=Construction
|RECORD=41|OwnerIndex=2532|IndexInSheet=12|OwnerPartId=-1|Location.X=1269|Location.Y=172|Color=8388608|FontID=1|IsHidden=T|Text=125°C|Name=Max Operating Temperature
|RECORD=41|OwnerIndex=2532|IndexInSheet=13|OwnerPartId=-1|Location.X=1269|Location.Y=172|Color=8388608|FontID=1|IsHidden=T|Text=No|Name=Radiation Hardening
|RECORD=41|OwnerIndex=2532|IndexInSheet=14|OwnerPartId=-1|Location.X=1269|Location.Y=172|Color=8388608|FontID=1|IsHidden=T|Text=0.5mm|Name=Depth
|RECORD=41|OwnerIndex=2532|IndexInSheet=15|OwnerPartId=-1|Location.X=1269|Location.Y=172|Color=8388608|FontID=1|IsHidden=T|Text=0.022inch|Name=Thickness
|RECORD=41|OwnerIndex=2532|IndexInSheet=16|OwnerPartId=-1|Location.X=1269|Location.Y=172|Color=8388608|FontID=1|IsHidden=T|Text=25V|Name=Voltage Rating (DC)
|RECORD=41|OwnerIndex=2532|IndexInSheet=17|OwnerPartId=-1|Location.X=1269|Location.Y=172|Color=8388608|FontID=1|IsHidden=T|Text=2|Name=Number of Pins
|RECORD=41|OwnerIndex=2532|IndexInSheet=18|OwnerPartId=-1|Location.X=1269|Location.Y=172|Color=8388608|FontID=1|IsHidden=T|Text=Lead Free|Name=Lead Free
|RECORD=41|OwnerIndex=2532|IndexInSheet=19|OwnerPartId=-1|Location.X=1269|Location.Y=172|Color=8388608|FontID=1|IsHidden=T|Text=-|Name=Series
|RECORD=41|OwnerIndex=2532|IndexInSheet=20|OwnerPartId=-1|Location.X=1269|Location.Y=172|Color=8388608|FontID=1|IsHidden=T|Text=No SVHC|Name=REACH SVHC
|RECORD=41|OwnerIndex=2532|IndexInSheet=21|OwnerPartId=-1|Location.X=1269|Location.Y=172|Color=8388608|FontID=1|IsHidden=T|Text=1mm|Name=Length
|RECORD=41|OwnerIndex=2532|IndexInSheet=22|OwnerPartId=-1|Location.X=1269|Location.Y=172|Color=8388608|FontID=1|IsHidden=T|Text=X7R|Name=Dielectric
|RECORD=41|OwnerIndex=2532|IndexInSheet=23|OwnerPartId=-1|Location.X=1269|Location.Y=172|Color=8388608|FontID=1|IsHidden=T|Text=Yes|Name=RoHS Compliant
|RECORD=41|OwnerIndex=2532|IndexInSheet=24|OwnerPartId=-1|Location.X=1269|Location.Y=172|Color=8388608|FontID=1|IsHidden=T|Text=Surface Mount|Name=Mount
|RECORD=41|OwnerIndex=2532|IndexInSheet=25|OwnerPartId=-1|Location.X=1269|Location.Y=172|Color=8388608|FontID=1|IsHidden=T|Text=Tape and Reel|Name=Packaging
|RECORD=41|OwnerIndex=2532|IndexInSheet=26|OwnerPartId=-1|Location.X=1269|Location.Y=172|Color=8388608|FontID=1|IsHidden=T|Text=0402|Name=Case/Package
|RECORD=41|OwnerIndex=2532|IndexInSheet=27|OwnerPartId=-1|Location.X=1269|Location.Y=172|Color=8388608|FontID=1|IsHidden=T|Text=0402|Name=Case Code (Imperial)
|RECORD=41|OwnerIndex=2532|IndexInSheet=28|OwnerPartId=-1|Location.X=1269|Location.Y=172|Color=8388608|FontID=1|IsHidden=T|Text=SMD/SMT|Name=Termination
|RECORD=41|OwnerIndex=2532|IndexInSheet=29|OwnerPartId=-1|Location.X=1269|Location.Y=172|Color=8388608|FontID=1|IsHidden=T|Text=0.02inch|Name=Width
|RECORD=41|OwnerIndex=2532|IndexInSheet=30|OwnerPartId=-1|Location.X=1269|Location.Y=172|Color=8388608|FontID=1|IsHidden=T|Text=1005|Name=Case Code (Metric)
|RECORD=41|OwnerIndex=2532|IndexInSheet=31|OwnerPartId=-1|Location.X=1269|Location.Y=172|Color=8388608|FontID=1|IsHidden=T|Text=10%|Name=Tolerance
|RECORD=34|OwnerIndex=2532|IndexInSheet=-1|OwnerPartId=-1|Location.X=1270|Location.Y=150|Orientation=1|Color=8388608|FontID=2|Text=C105|Name=Designator|ReadOnlyState=1
|RECORD=41|OwnerIndex=2532|IndexInSheet=-1|OwnerPartId=1|Location.X=1300|Location.Y=135|Orientation=1|Color=8388608|FontID=2|Text=0.1uF_25V_0402|Name=Comment
|RECORD=44|OwnerIndex=2532
|RECORD=45|OwnerIndex=2569|IndexInSheet=-1|UseComponentLibrary=T|ModelName=FP-0402-L_1_0_1-W_0_5_0_1-IPC_C|ModelType=PCBLIB|DatafileCount=1|ModelDatafileEntity0=FP-0402-L_1_0_1-W_0_5_0_1-IPC_C|ModelDatafileKind0=PCBLib|IsCurrent=T|DatalinksLocked=T|DatabaseDatalinksLocked=T
|RECORD=46|OwnerIndex=2570
|RECORD=48|OwnerIndex=2570
|RECORD=45|OwnerIndex=2569|IndexInSheet=-1|UseComponentLibrary=T|ModelName=FP-0402-L_1_0_1-W_0_5_0_1-IPC_B|ModelType=PCBLIB|DatafileCount=1|ModelDatafileEntity0=FP-0402-L_1_0_1-W_0_5_0_1-IPC_B|ModelDatafileKind0=PCBLib|DatalinksLocked=T|DatabaseDatalinksLocked=T
|RECORD=46|OwnerIndex=2573
|RECORD=48|OwnerIndex=2573
|RECORD=45|OwnerIndex=2569|IndexInSheet=-1|UseComponentLibrary=T|ModelName=FP-0402-L_1_0_1-W_0_5_0_1-MFG|ModelType=PCBLIB|DatafileCount=1|ModelDatafileEntity0=FP-0402-L_1_0_1-W_0_5_0_1-MFG|ModelDatafileKind0=PCBLib|DatalinksLocked=T|DatabaseDatalinksLocked=T
|RECORD=46|OwnerIndex=2576
|RECORD=48|OwnerIndex=2576
|RECORD=45|OwnerIndex=2569|IndexInSheet=-1|UseComponentLibrary=T|ModelName=FP-0402-L_1_0_1-W_0_5_0_1-IPC_A|ModelType=PCBLIB|DatafileCount=1|ModelDatafileEntity0=FP-0402-L_1_0_1-W_0_5_0_1-IPC_A|ModelDatafileKind0=PCBLib|DatalinksLocked=T|DatabaseDatalinksLocked=T
|RECORD=46|OwnerIndex=2579
|RECORD=48|OwnerIndex=2579
|RECORD=27|IndexInSheet=173|OwnerPartId=-1|LineWidth=1|Color=8388608|LocationCount=3|X1=1090|Y1=200|X2=1120|Y2=200|X3=1120|Y3=170
|RECORD=27|IndexInSheet=174|OwnerPartId=-1|LineWidth=1|Color=8388608|LocationCount=3|X1=1120|Y1=200|X2=1160|Y2=200|X3=1160|Y3=170
|RECORD=27|IndexInSheet=175|OwnerPartId=-1|LineWidth=1|Color=8388608|LocationCount=3|X1=1160|Y1=200|X2=1200|Y2=200|X3=1200|Y3=170
|RECORD=27|IndexInSheet=176|OwnerPartId=-1|LineWidth=1|Color=8388608|LocationCount=3|X1=1200|Y1=200|X2=1240|Y2=200|X3=1240|Y3=170
|RECORD=27|IndexInSheet=177|OwnerPartId=-1|LineWidth=1|Color=8388608|LocationCount=3|X1=1240|Y1=200|X2=1280|Y2=200|X3=1280|Y3=170
|RECORD=27|IndexInSheet=178|OwnerPartId=-1|LineWidth=1|Color=8388608|LocationCount=3|X1=1120|Y1=150|X2=1120|Y2=130|X3=1090|Y3=130
|RECORD=27|IndexInSheet=179|OwnerPartId=-1|LineWidth=1|Color=8388608|LocationCount=3|X1=1160|Y1=150|X2=1160|Y2=130|X3=1120|Y3=130
|RECORD=27|IndexInSheet=180|OwnerPartId=-1|LineWidth=1|Color=8388608|LocationCount=5|X1=1280|Y1=150|X2=1280|Y2=130|X3=1240|Y3=130|X4=1200|Y4=130|X5=1160|Y5=130
|RECORD=27|IndexInSheet=181|OwnerPartId=-1|LineWidth=1|Color=8388608|LocationCount=2|X1=1200|Y1=150|X2=1200|Y2=130
|RECORD=27|IndexInSheet=182|OwnerPartId=-1|LineWidth=1|Color=8388608|LocationCount=2|X1=1240|Y1=150|X2=1240|Y2=130
|RECORD=27|IndexInSheet=183|OwnerPartId=-1|LineWidth=1|Color=8388608|LocationCount=2|X1=430|Y1=700|X2=560|Y2=700
|RECORD=27|IndexInSheet=184|OwnerPartId=-1|LineWidth=1|Color=8388608|LocationCount=2|X1=430|Y1=680|X2=560|Y2=680
|RECORD=17|IndexInSheet=185|OwnerPartId=-1|ShowNetName=T|Location.X=1090|Location.Y=810|Orientation=1|Color=128|FontID=1|Text=GNSS2_P3V3
|RECORD=29|IndexInSheet=-1|OwnerPartId=-1|Location.X=160|Location.Y=130|Color=128
|RECORD=29|IndexInSheet=-1|OwnerPartId=-1|Location.X=160|Location.Y=170|Color=128
|RECORD=29|IndexInSheet=-1|OwnerPartId=-1|Location.X=160|Location.Y=190|Color=128
|RECORD=29|IndexInSheet=-1|OwnerPartId=-1|Location.X=160|Location.Y=330|Color=128
|RECORD=29|IndexInSheet=-1|OwnerPartId=-1|Location.X=160|Location.Y=390|Color=128
|RECORD=29|IndexInSheet=-1|OwnerPartId=-1|Location.X=160|Location.Y=450|Color=128
|RECORD=29|IndexInSheet=-1|OwnerPartId=-1|Location.X=160|Location.Y=510|Color=128
|RECORD=29|IndexInSheet=-1|OwnerPartId=-1|Location.X=160|Location.Y=570|Color=128
|RECORD=29|IndexInSheet=-1|OwnerPartId=-1|Location.X=160|Location.Y=630|Color=128
|RECORD=29|IndexInSheet=-1|OwnerPartId=-1|Location.X=160|Location.Y=710|Color=128
|RECORD=29|IndexInSheet=-1|OwnerPartId=-1|Location.X=160|Location.Y=770|Color=128
|RECORD=29|IndexInSheet=-1|OwnerPartId=-1|Location.X=460|Location.Y=130|Color=128
|RECORD=29|IndexInSheet=-1|OwnerPartId=-1|Location.X=460|Location.Y=180|Color=128
|RECORD=29|IndexInSheet=-1|OwnerPartId=-1|Location.X=460|Location.Y=200|Color=128
|RECORD=29|IndexInSheet=-1|OwnerPartId=-1|Location.X=460|Location.Y=570|Color=128
|RECORD=29|IndexInSheet=-1|OwnerPartId=-1|Location.X=460|Location.Y=780|Color=128
|RECORD=29|IndexInSheet=-1|OwnerPartId=-1|Location.X=460|Location.Y=800|Color=128
|RECORD=29|IndexInSheet=-1|OwnerPartId=-1|Location.X=480|Location.Y=500|Color=128
|RECORD=29|IndexInSheet=-1|OwnerPartId=-1|Location.X=480|Location.Y=570|Color=128
|RECORD=29|IndexInSheet=-1|OwnerPartId=-1|Location.X=490|Location.Y=130|Color=128
|RECORD=29|IndexInSheet=-1|OwnerPartId=-1|Location.X=490|Location.Y=200|Color=128
|RECORD=29|IndexInSheet=-1|OwnerPartId=-1|Location.X=500|Location.Y=480|Color=128
|RECORD=29|IndexInSheet=-1|OwnerPartId=-1|Location.X=500|Location.Y=570|Color=128
|RECORD=29|IndexInSheet=-1|OwnerPartId=-1|Location.X=520|Location.Y=460|Color=128
|RECORD=29|IndexInSheet=-1|OwnerPartId=-1|Location.X=530|Location.Y=130|Color=128
|RECORD=29|IndexInSheet=-1|OwnerPartId=-1|Location.X=530|Location.Y=200|Color=128
|RECORD=29|IndexInSheet=-1|OwnerPartId=-1|Location.X=570|Location.Y=130|Color=128
|RECORD=29|IndexInSheet=-1|OwnerPartId=-1|Location.X=570|Location.Y=200|Color=128
|RECORD=29|IndexInSheet=-1|OwnerPartId=-1|Location.X=610|Location.Y=130|Color=128
|RECORD=29|IndexInSheet=-1|OwnerPartId=-1|Location.X=610|Location.Y=200|Color=128
|RECORD=29|IndexInSheet=-1|OwnerPartId=-1|Location.X=790|Location.Y=120|Color=128
|RECORD=29|IndexInSheet=-1|OwnerPartId=-1|Location.X=790|Location.Y=160|Color=128
|RECORD=29|IndexInSheet=-1|OwnerPartId=-1|Location.X=790|Location.Y=180|Color=128
|RECORD=29|IndexInSheet=-1|OwnerPartId=-1|Location.X=790|Location.Y=320|Color=128
|RECORD=29|IndexInSheet=-1|OwnerPartId=-1|Location.X=790|Location.Y=380|Color=128
|RECORD=29|IndexInSheet=-1|OwnerPartId=-1|Location.X=790|Location.Y=440|Color=128
|RECORD=29|IndexInSheet=-1|OwnerPartId=-1|Location.X=790|Location.Y=500|Color=128
|RECORD=29|IndexInSheet=-1|OwnerPartId=-1|Location.X=790|Location.Y=560|Color=128
|RECORD=29|IndexInSheet=-1|OwnerPartId=-1|Location.X=790|Location.Y=620|Color=128
|RECORD=29|IndexInSheet=-1|OwnerPartId=-1|Location.X=790|Location.Y=700|Color=128
|RECORD=29|IndexInSheet=-1|OwnerPartId=-1|Location.X=790|Location.Y=760|Color=128
|RECORD=29|IndexInSheet=-1|OwnerPartId=-1|Location.X=1090|Location.Y=130|Color=128
|RECORD=29|IndexInSheet=-1|OwnerPartId=-1|Location.X=1090|Location.Y=170|Color=128
|RECORD=29|IndexInSheet=-1|OwnerPartId=-1|Location.X=1090|Location.Y=190|Color=128
|RECORD=29|IndexInSheet=-1|OwnerPartId=-1|Location.X=1090|Location.Y=200|Color=128
|RECORD=29|IndexInSheet=-1|OwnerPartId=-1|Location.X=1090|Location.Y=560|Color=128
|RECORD=29|IndexInSheet=-1|OwnerPartId=-1|Location.X=1090|Location.Y=770|Color=128
|RECORD=29|IndexInSheet=-1|OwnerPartId=-1|Location.X=1090|Location.Y=790|Color=128
|RECORD=29|IndexInSheet=-1|OwnerPartId=-1|Location.X=1110|Location.Y=490|Color=128
|RECORD=29|IndexInSheet=-1|OwnerPartId=-1|Location.X=1110|Location.Y=560|Color=128
|RECORD=29|IndexInSheet=-1|OwnerPartId=-1|Location.X=1120|Location.Y=130|Color=128
|RECORD=29|IndexInSheet=-1|OwnerPartId=-1|Location.X=1120|Location.Y=200|Color=128
|RECORD=29|IndexInSheet=-1|OwnerPartId=-1|Location.X=1130|Location.Y=470|Color=128
|RECORD=29|IndexInSheet=-1|OwnerPartId=-1|Location.X=1130|Location.Y=560|Color=128
|RECORD=29|IndexInSheet=-1|OwnerPartId=-1|Location.X=1150|Location.Y=450|Color=128
|RECORD=29|IndexInSheet=-1|OwnerPartId=-1|Location.X=1160|Location.Y=130|Color=128
|RECORD=29|IndexInSheet=-1|OwnerPartId=-1|Location.X=1160|Location.Y=200|Color=128
|RECORD=29|IndexInSheet=-1|OwnerPartId=-1|Location.X=1200|Location.Y=130|Color=128
|RECORD=29|IndexInSheet=-1|OwnerPartId=-1|Location.X=1200|Location.Y=200|Color=128
|RECORD=29|IndexInSheet=-1|OwnerPartId=-1|Location.X=1240|Location.Y=130|Color=128
|RECORD=29|IndexInSheet=-1|OwnerPartId=-1|Location.X=1240|Location.Y=200|Color=128